FILE_TYPE = MACRO_DRAWING;
SET COLOR_WIRE YELLOW;
SET COLOR_PROP MONO;
SET COLOR_DOT WHITE;
SET COLOR_ARC YELLOW;
SET COLOR_BODY GREEN;
SET COLOR_NOTE MONO;
SET PROP_DISPLAY VALUE;
SET PAGE_NUMBER P149;
FORCEADD H5AN4G6NAFR-TFC-GP..1
(-1850 2625);
FORCEPROP 1 LAST LOCATION U25W5
J 0
(-2175 4175);
DISPLAY 0.617021 (-2175 4175);
PAINT GREEN (-2175 4175);
FORCEPROP 1 LAST VALUE H5AN4G6NAFR-TFC-GP
J 0
(-2175 1050);
DISPLAY 0.617021 (-2175 1050);
PAINT GREEN (-2175 1050);
FORCEPROP 1 LAST PACK_TYPE MEMORY-G2
J 0
(-1850 2625);
DISPLAY 0.617021 (-1850 2625);
PAINT GREEN (-1850 2625);
DISPLAY INVISIBLE (-1850 2625);
FORCEPROP 1 LAST PART_NUMBER 072.00546.0A0U
J 0
(-1850 2625);
DISPLAY 0.617021 (-1850 2625);
PAINT GREEN (-1850 2625);
DISPLAY INVISIBLE (-1850 2625);
FORCEPROP 2 LAST CDS_LIB w_hdl
J 0
(-1850 2625);
PAINT MONO (-1850 2625);
DISPLAY INVISIBLE (-1850 2625);
FORCEPROP 1 LAST CDS_LMAN_SYM_OUTLINE -325,1525,325,-1525
J 0
(-1850 2625);
DISPLAY 0.468085 (-1850 2625);
PAINT GREEN (-1850 2625);
DISPLAY INVISIBLE (-1850 2625);
FORCEPROP 1 LAST PATH I1
J 0
(-1850 2625);
DISPLAY 0.617021 (-1850 2625);
PAINT GREEN (-1850 2625);
DISPLAY INVISIBLE (-1850 2625);
FORCEADD OFFPAGE..3
(-875 3650);
FORCEPROP 2 LAST $XR1 149 
J 0
(-541 3650);
DISPLAY 0.638298 (-541 3650);
PAINT MONO (-541 3650);
FORCEPROP 2 LAST $XR0 143 
J 0
(-661 3650);
DISPLAY 0.638298 (-661 3650);
PAINT MONO (-661 3650);
FORCEPROP 1 LAST COMMENT_BODY TRUE
J 0
(-925 3550);
DISPLAY 0.872340 (-925 3550);
PAINT GREEN (-925 3550);
DISPLAY INVISIBLE (-925 3550);
FORCEPROP 1 LAST OFFPAGE TRUE
J 0
(-550 3525);
DISPLAY 0.872340 (-550 3525);
PAINT GREEN (-550 3525);
DISPLAY INVISIBLE (-550 3525);
FORCEPROP 2 LAST CDS_LIB mstr_standard
J 0
(-875 3650);
PAINT MONO (-875 3650);
DISPLAY INVISIBLE (-875 3650);
FORCEPROP 2 LAST PATH I10
J 0
(-525 3700);
DISPLAY 1.021277 (-525 3700);
PAINT ORANGE (-525 3700);
DISPLAY INVISIBLE (-525 3700);
FORCEADD P3V3_STBY..1
(-6200 2550);
FORCEPROP 3 LASTPIN (-6200 2500) SIG_NAME P3V3_STBY\g
J 0
(-6190 2510);
DISPLAY 0.659574 (-6190 2510);
PAINT MONO (-6190 2510);
DISPLAY INVISIBLE (-6190 2510);
FORCEPROP 1 LAST HDL_POWER P3V3_STBY
J 0
(-6500 2425);
DISPLAY 0.872340 (-6500 2425);
PAINT ORANGE (-6500 2425);
DISPLAY INVISIBLE (-6500 2425);
FORCEPROP 1 LAST BODY_TYPE PLUMBING
J 0
(-6245 2507);
DISPLAY 0.340426 (-6245 2507);
PAINT GREEN (-6245 2507);
DISPLAY INVISIBLE (-6245 2507);
FORCEPROP 1 LAST VOLTAGE 3.3V
J 0
(-6245 2507);
DISPLAY 0.340426 (-6245 2507);
PAINT SKYBLUE (-6245 2507);
DISPLAY INVISIBLE (-6245 2507);
FORCEPROP 1 LAST SIZE 1B
J 0
(-6155 2572);
DISPLAY 0.340426 (-6155 2572);
PAINT GREEN (-6155 2572);
DISPLAY INVISIBLE (-6155 2572);
FORCEPROP 2 LAST CDS_LIB mstr_symbols
J 0
(-6200 2550);
PAINT MONO (-6200 2550);
DISPLAY INVISIBLE (-6200 2550);
FORCEPROP 1 LAST PATH I108
J 0
(-6155 2552);
DISPLAY 0.340426 (-6155 2552);
PAINT GREEN (-6155 2552);
DISPLAY INVISIBLE (-6155 2552);
FORCEADD FET_N_DUAL..5
(-5600 2250);
FORCEPROP 1 LAST PART_NUMBER E40049-001
J 0
(-5400 2050);
DISPLAY 0.617021 (-5400 2050);
PAINT BLUE (-5400 2050);
FORCEPROP 1 LASTPIN (-5800 2150) $PN 5
J 2
(-5797 2165);
DISPLAY 0.617021 (-5797 2165);
PAINT WHITE (-5797 2165);
FORCEPROP 1 LASTPIN (-5600 2450) $PN 3
J 2
(-5547 2415);
DISPLAY 0.617021 (-5547 2415);
PAINT WHITE (-5547 2415);
FORCEPROP 1 LASTPIN (-5600 2050) $PN 4
J 2
(-5542 2050);
DISPLAY 0.617021 (-5542 2050);
PAINT WHITE (-5542 2050);
FORCEPROP 1 LAST MATERIAL FET
J 0
(-5400 2150);
DISPLAY 0.617021 (-5400 2150);
PAINT SKYBLUE (-5400 2150);
FORCEPROP 1 LAST VALUE NTJD4001N
J 0
(-5400 2200);
DISPLAY 0.617021 (-5400 2200);
PAINT SKYBLUE (-5400 2200);
FORCEPROP 1 LAST LOCATION Q9E1
J 0
(-5400 2250);
DISPLAY 0.617021 (-5400 2250);
PAINT AQUA (-5400 2250);
FORCEPROP 0 LAST CDS_SEC 2
J 0
(-5400 2300);
PAINT MONO (-5400 2300);
DISPLAY INVISIBLE (-5400 2300);
FORCEPROP 2 LAST CDS_LIB mstr_discrete
J 0
(-5600 2250);
PAINT MONO (-5600 2250);
DISPLAY INVISIBLE (-5600 2250);
FORCEPROP 1 LAST PACK_TYPE SMLF
J 0
(-5400 2100);
DISPLAY 0.978723 (-5400 2100);
PAINT SKYBLUE (-5400 2100);
DISPLAY INVISIBLE (-5400 2100);
FORCEPROP 2 LAST CDS_LOCATION Q9E1
J 0
(-5400 2250);
DISPLAY 0.617021 (-5400 2250);
PAINT AQUA (-5400 2250);
DISPLAY INVISIBLE (-5400 2250);
FORCEPROP 2 LAST SEC 2
J 0
(-5400 2350);
DISPLAY 0.680851 (-5400 2350);
PAINT MONO (-5400 2350);
DISPLAY INVISIBLE (-5400 2350);
FORCEPROP 2 LAST BOM_COST SM_CONTROLLER
J 0
(-5400 2350);
DISPLAY 1.021277 (-5400 2350);
PAINT ORANGE (-5400 2350);
DISPLAY INVISIBLE (-5400 2350);
FORCEPROP 2 LAST SEC_TYPE SMLF
J 0
(-5400 2350);
DISPLAY 1.021277 (-5400 2350);
PAINT ORANGE (-5400 2350);
DISPLAY INVISIBLE (-5400 2350);
FORCEPROP 2 LAST ROOM BMC
J 0
(-5400 2300);
DISPLAY 1.021277 (-5400 2300);
PAINT ORANGE (-5400 2300);
DISPLAY INVISIBLE (-5400 2300);
FORCEPROP 1 LAST PATH I109
J 0
(-5400 2300);
DISPLAY 0.978723 (-5400 2300);
PAINT BLUE (-5400 2300);
DISPLAY INVISIBLE (-5400 2300);
FORCEADD OFFPAGE..3
(-875 3550);
FORCEPROP 2 LAST $XR0 143 
J 0
(-661 3550);
DISPLAY 0.638298 (-661 3550);
PAINT MONO (-661 3550);
FORCEPROP 2 LAST $XR1 149 
J 0
(-541 3550);
DISPLAY 0.638298 (-541 3550);
PAINT MONO (-541 3550);
FORCEPROP 1 LAST COMMENT_BODY TRUE
J 0
(-925 3450);
DISPLAY 0.872340 (-925 3450);
PAINT GREEN (-925 3450);
DISPLAY INVISIBLE (-925 3450);
FORCEPROP 1 LAST OFFPAGE TRUE
J 0
(-550 3425);
DISPLAY 0.872340 (-550 3425);
PAINT GREEN (-550 3425);
DISPLAY INVISIBLE (-550 3425);
FORCEPROP 2 LAST CDS_LIB mstr_standard
J 0
(-875 3550);
PAINT MONO (-875 3550);
DISPLAY INVISIBLE (-875 3550);
FORCEPROP 2 LAST PATH I11
J 0
(-525 3600);
DISPLAY 1.021277 (-525 3600);
PAINT ORANGE (-525 3600);
DISPLAY INVISIBLE (-525 3600);
FORCEADD GND..1
(-5600 1925);
FORCEPROP 3 LASTPIN (-5600 1975) SIG_NAME GND\g
J 0
(-5590 1985);
DISPLAY 0.659574 (-5590 1985);
PAINT MONO (-5590 1985);
DISPLAY INVISIBLE (-5590 1985);
FORCEPROP 1 LAST HDL_POWER GND
J 0
(-5600 2075);
DISPLAY 0.872340 (-5600 2075);
PAINT GREEN (-5600 2075);
DISPLAY INVISIBLE (-5600 2075);
FORCEPROP 1 LAST BODY_TYPE PLUMBING
J 0
(-5645 1882);
DISPLAY 0.340426 (-5645 1882);
PAINT GREEN (-5645 1882);
DISPLAY INVISIBLE (-5645 1882);
FORCEPROP 1 LAST VOLTAGE 0.0V
J 0
(-5645 1882);
DISPLAY 0.340426 (-5645 1882);
PAINT SKYBLUE (-5645 1882);
DISPLAY INVISIBLE (-5645 1882);
FORCEPROP 2 LAST CDS_LIB mstr_symbols
J 0
(-5600 1925);
PAINT ORANGE (-5600 1925);
DISPLAY INVISIBLE (-5600 1925);
FORCEPROP 1 LAST SIZE 1B
J 0
(-5525 1875);
DISPLAY 0.872340 (-5525 1875);
PAINT AQUA (-5525 1875);
DISPLAY INVISIBLE (-5525 1875);
FORCEPROP 1 LAST PATH I110
J 0
(-5525 1925);
DISPLAY 0.872340 (-5525 1925);
PAINT AQUA (-5525 1925);
DISPLAY INVISIBLE (-5525 1925);
FORCEADD RES..2
(-6200 2325);
FORCEPROP 1 LAST VALUE 4.75K
J 0
(-6155 2400);
DISPLAY 0.617021 (-6155 2400);
PAINT SKYBLUE (-6155 2400);
FORCEPROP 1 LAST MATERIAL CHIP
J 0
(-6160 2250);
DISPLAY 0.617021 (-6160 2250);
PAINT SKYBLUE (-6160 2250);
FORCEPROP 1 LAST PART_NUMBER G21796-072
J 0
(-6160 2200);
DISPLAY 0.617021 (-6160 2200);
PAINT BLUE (-6160 2200);
FORCEPROP 1 LAST PACK_TYPE 0402
J 0
(-6160 2150);
DISPLAY 0.617021 (-6160 2150);
PAINT SKYBLUE (-6160 2150);
FORCEPROP 1 LASTPIN (-6200 2225) $PN 2
J 0
(-6195 2235);
DISPLAY 0.617021 (-6195 2235);
PAINT ORANGE (-6195 2235);
FORCEPROP 1 LASTPIN (-6200 2425) $PN 1
J 0
(-6195 2387);
DISPLAY 0.617021 (-6195 2387);
PAINT ORANGE (-6195 2387);
FORCEPROP 1 LAST TOLERANCE 1%
J 0
(-6155 2350);
DISPLAY 0.617021 (-6155 2350);
PAINT SKYBLUE (-6155 2350);
FORCEPROP 1 LAST LOCATION R9E21
J 0
(-6155 2450);
DISPLAY 0.617021 (-6155 2450);
PAINT AQUA (-6155 2450);
FORCEPROP 1 LAST WATTAGE 1/16W
J 0
(-6160 2300);
DISPLAY 0.617021 (-6160 2300);
PAINT SKYBLUE (-6160 2300);
FORCEPROP 0 LAST CDS_SEC 1
J 0
(-6150 2500);
PAINT MONO (-6150 2500);
DISPLAY INVISIBLE (-6150 2500);
FORCEPROP 2 LAST CDS_LIB mstr_discrete
J 0
(-6200 2325);
PAINT MONO (-6200 2325);
DISPLAY INVISIBLE (-6200 2325);
FORCEPROP 2 LAST CDS_LOCATION R9E21
J 0
(-6155 2450);
DISPLAY 0.617021 (-6155 2450);
PAINT AQUA (-6155 2450);
DISPLAY INVISIBLE (-6155 2450);
FORCEPROP 0 LAST ROOM BMC
J 0
(-6150 2550);
DISPLAY 1.021277 (-6150 2550);
PAINT ORANGE (-6150 2550);
DISPLAY INVISIBLE (-6150 2550);
FORCEPROP 2 LAST SEC 1
J 0
(-6150 2550);
DISPLAY 0.680851 (-6150 2550);
PAINT MONO (-6150 2550);
DISPLAY INVISIBLE (-6150 2550);
FORCEPROP 0 LAST BOM_COST SM_CONTROLLER
J 0
(-6150 2650);
DISPLAY 1.021277 (-6150 2650);
PAINT ORANGE (-6150 2650);
DISPLAY INVISIBLE (-6150 2650);
FORCEPROP 2 LAST SEC_TYPE 0402
J 0
(-6150 2550);
DISPLAY 1.021277 (-6150 2550);
PAINT ORANGE (-6150 2550);
DISPLAY INVISIBLE (-6150 2550);
FORCEPROP 1 LAST PATH I111
J 0
(-6150 2500);
DISPLAY 0.978723 (-6150 2500);
PAINT WHITE (-6150 2500);
DISPLAY INVISIBLE (-6150 2500);
FORCEADD GND..1
(-6200 1525);
FORCEPROP 3 LASTPIN (-6200 1575) SIG_NAME GND\g
J 0
(-6190 1585);
DISPLAY 0.659574 (-6190 1585);
PAINT MONO (-6190 1585);
DISPLAY INVISIBLE (-6190 1585);
FORCEPROP 1 LAST HDL_POWER GND
J 0
(-6200 1675);
DISPLAY 0.872340 (-6200 1675);
PAINT GREEN (-6200 1675);
DISPLAY INVISIBLE (-6200 1675);
FORCEPROP 1 LAST BODY_TYPE PLUMBING
J 0
(-6245 1482);
DISPLAY 0.340426 (-6245 1482);
PAINT GREEN (-6245 1482);
DISPLAY INVISIBLE (-6245 1482);
FORCEPROP 1 LAST VOLTAGE 0.0V
J 0
(-6245 1482);
DISPLAY 0.340426 (-6245 1482);
PAINT SKYBLUE (-6245 1482);
DISPLAY INVISIBLE (-6245 1482);
FORCEPROP 1 LAST SIZE 1B
J 0
(-6125 1475);
DISPLAY 0.872340 (-6125 1475);
PAINT AQUA (-6125 1475);
DISPLAY INVISIBLE (-6125 1475);
FORCEPROP 2 LAST CDS_LIB mstr_symbols
J 0
(-6200 1525);
PAINT MONO (-6200 1525);
DISPLAY INVISIBLE (-6200 1525);
FORCEPROP 1 LAST PATH I112
J 0
(-6125 1525);
DISPLAY 0.872340 (-6125 1525);
PAINT AQUA (-6125 1525);
DISPLAY INVISIBLE (-6125 1525);
FORCEADD FET_N_DUAL..5
(-6200 1825);
FORCEPROP 1 LASTPIN (-6400 1725) $PN 2
J 2
(-6397 1740);
DISPLAY 0.617021 (-6397 1740);
PAINT WHITE (-6397 1740);
FORCEPROP 1 LASTPIN (-6200 2025) $PN 6
J 2
(-6147 1990);
DISPLAY 0.617021 (-6147 1990);
PAINT WHITE (-6147 1990);
FORCEPROP 1 LAST MATERIAL FET
J 0
(-6000 1725);
DISPLAY 0.617021 (-6000 1725);
PAINT SKYBLUE (-6000 1725);
FORCEPROP 1 LASTPIN (-6200 1625) $PN 1
J 2
(-6142 1625);
DISPLAY 0.617021 (-6142 1625);
PAINT WHITE (-6142 1625);
FORCEPROP 1 LAST VALUE NTJD4001N
J 0
(-6000 1775);
DISPLAY 0.617021 (-6000 1775);
PAINT SKYBLUE (-6000 1775);
FORCEPROP 1 LAST LOCATION Q9E1
J 0
(-6000 1825);
DISPLAY 0.617021 (-6000 1825);
PAINT AQUA (-6000 1825);
FORCEPROP 1 LAST PART_NUMBER E40049-001
J 0
(-6000 1625);
DISPLAY 0.617021 (-6000 1625);
PAINT BLUE (-6000 1625);
FORCEPROP 0 LAST CDS_SEC 1
J 0
(-6000 1875);
PAINT MONO (-6000 1875);
DISPLAY INVISIBLE (-6000 1875);
FORCEPROP 2 LAST CDS_LIB mstr_discrete
J 0
(-6200 1825);
PAINT MONO (-6200 1825);
DISPLAY INVISIBLE (-6200 1825);
FORCEPROP 2 LAST CDS_LOCATION Q9E1
J 0
(-6000 1825);
DISPLAY 0.617021 (-6000 1825);
PAINT AQUA (-6000 1825);
DISPLAY INVISIBLE (-6000 1825);
FORCEPROP 0 LAST ROOM BMC
J 0
(-6000 1925);
DISPLAY 1.021277 (-6000 1925);
PAINT ORANGE (-6000 1925);
DISPLAY INVISIBLE (-6000 1925);
FORCEPROP 1 LAST PACK_TYPE SMLF
J 0
(-6000 1675);
DISPLAY 0.978723 (-6000 1675);
PAINT SKYBLUE (-6000 1675);
DISPLAY INVISIBLE (-6000 1675);
FORCEPROP 2 LAST SEC_TYPE SMLF
J 0
(-6000 1925);
DISPLAY 1.021277 (-6000 1925);
PAINT ORANGE (-6000 1925);
DISPLAY INVISIBLE (-6000 1925);
FORCEPROP 2 LAST SEC 1
J 0
(-6000 1925);
DISPLAY 0.680851 (-6000 1925);
PAINT MONO (-6000 1925);
DISPLAY INVISIBLE (-6000 1925);
FORCEPROP 0 LAST BOM_COST SM_CONTROLLER
J 0
(-6000 2025);
DISPLAY 1.021277 (-6000 2025);
PAINT ORANGE (-6000 2025);
DISPLAY INVISIBLE (-6000 2025);
FORCEPROP 1 LAST PATH I113
J 0
(-6000 1875);
DISPLAY 0.978723 (-6000 1875);
PAINT BLUE (-6000 1875);
DISPLAY INVISIBLE (-6000 1875);
FORCEADD OFFPAGE..3
R 2
(-2975 1450);
FORCEPROP 2 LAST $XR0 143 
J 0
(-3285 1450);
DISPLAY 0.638298 (-3285 1450);
PAINT MONO (-3285 1450);
FORCEPROP 2 LAST PATH I114
J 0
(-3275 1500);
DISPLAY 1.021277 (-3275 1500);
PAINT ORANGE (-3275 1500);
DISPLAY INVISIBLE (-3275 1500);
FORCEPROP 2 LAST CDS_LIB mstr_standard
J 0
(-2975 1450);
PAINT MONO (-2975 1450);
DISPLAY INVISIBLE (-2975 1450);
FORCEPROP 2 LAST ROOM BMC
J 2
(-3450 1500);
PAINT MONO (-3450 1500);
DISPLAY INVISIBLE (-3450 1500);
FORCEPROP 2 LAST BOM_COST SM_CONTROLLER
J 2
(-3450 1500);
PAINT MONO (-3450 1500);
DISPLAY INVISIBLE (-3450 1500);
FORCEPROP 1 LAST OFFPAGE TRUE
J 2
(-3300 1325);
PAINT GREEN (-3300 1325);
DISPLAY INVISIBLE (-3300 1325);
FORCEPROP 1 LAST COMMENT_BODY TRUE
J 2
(-2925 1350);
DISPLAY 1.170213 (-2925 1350);
PAINT GREEN (-2925 1350);
DISPLAY INVISIBLE (-2925 1350);
FORCEADD OFFPAGE..3
R 2
(-2975 1400);
FORCEPROP 2 LAST $XR0 143 
J 0
(-3285 1400);
DISPLAY 0.638298 (-3285 1400);
PAINT MONO (-3285 1400);
FORCEPROP 2 LAST PATH I115
J 0
(-3275 1450);
DISPLAY 1.021277 (-3275 1450);
PAINT ORANGE (-3275 1450);
DISPLAY INVISIBLE (-3275 1450);
FORCEPROP 2 LAST CDS_LIB mstr_standard
J 0
(-2975 1400);
PAINT MONO (-2975 1400);
DISPLAY INVISIBLE (-2975 1400);
FORCEPROP 2 LAST ROOM BMC
J 2
(-3450 1450);
PAINT MONO (-3450 1450);
DISPLAY INVISIBLE (-3450 1450);
FORCEPROP 2 LAST BOM_COST SM_CONTROLLER
J 2
(-3450 1450);
PAINT MONO (-3450 1450);
DISPLAY INVISIBLE (-3450 1450);
FORCEPROP 1 LAST OFFPAGE TRUE
J 2
(-3300 1275);
PAINT GREEN (-3300 1275);
DISPLAY INVISIBLE (-3300 1275);
FORCEPROP 1 LAST COMMENT_BODY TRUE
J 2
(-2925 1300);
DISPLAY 1.170213 (-2925 1300);
PAINT GREEN (-2925 1300);
DISPLAY INVISIBLE (-2925 1300);
FORCEADD OFFPAGE..3
R 2
(-2975 1250);
FORCEPROP 2 LAST $XR0 143 
J 0
(-3285 1250);
DISPLAY 0.638298 (-3285 1250);
PAINT MONO (-3285 1250);
FORCEPROP 2 LAST $XR1 149 
J 0
(-3405 1250);
DISPLAY 0.638298 (-3405 1250);
PAINT MONO (-3405 1250);
FORCEPROP 2 LAST PATH I116
J 0
(-3275 1300);
DISPLAY 1.021277 (-3275 1300);
PAINT ORANGE (-3275 1300);
DISPLAY INVISIBLE (-3275 1300);
FORCEPROP 2 LAST BOM_COST SM_CONTROLLER
J 2
(-3450 1300);
PAINT MONO (-3450 1300);
DISPLAY INVISIBLE (-3450 1300);
FORCEPROP 2 LAST ROOM BMC
J 2
(-3450 1300);
PAINT MONO (-3450 1300);
DISPLAY INVISIBLE (-3450 1300);
FORCEPROP 2 LAST CDS_LIB mstr_standard
J 0
(-2975 1250);
PAINT MONO (-2975 1250);
DISPLAY INVISIBLE (-2975 1250);
FORCEPROP 1 LAST OFFPAGE TRUE
J 2
(-3300 1125);
PAINT GREEN (-3300 1125);
DISPLAY INVISIBLE (-3300 1125);
FORCEPROP 1 LAST COMMENT_BODY TRUE
J 2
(-2925 1150);
DISPLAY 1.170213 (-2925 1150);
PAINT GREEN (-2925 1150);
DISPLAY INVISIBLE (-2925 1150);
FORCEADD OFFPAGE..3
R 2
(-2975 1200);
FORCEPROP 2 LAST $XR0 143 
J 0
(-3285 1200);
DISPLAY 0.638298 (-3285 1200);
PAINT MONO (-3285 1200);
FORCEPROP 2 LAST $XR1 149 
J 0
(-3405 1200);
DISPLAY 0.638298 (-3405 1200);
PAINT MONO (-3405 1200);
FORCEPROP 2 LAST PATH I117
J 0
(-3275 1250);
DISPLAY 1.021277 (-3275 1250);
PAINT ORANGE (-3275 1250);
DISPLAY INVISIBLE (-3275 1250);
FORCEPROP 2 LAST BOM_COST SM_CONTROLLER
J 2
(-3450 1250);
PAINT MONO (-3450 1250);
DISPLAY INVISIBLE (-3450 1250);
FORCEPROP 2 LAST ROOM BMC
J 2
(-3450 1250);
PAINT MONO (-3450 1250);
DISPLAY INVISIBLE (-3450 1250);
FORCEPROP 2 LAST CDS_LIB mstr_standard
J 0
(-2975 1200);
PAINT MONO (-2975 1200);
DISPLAY INVISIBLE (-2975 1200);
FORCEPROP 1 LAST OFFPAGE TRUE
J 2
(-3300 1075);
PAINT GREEN (-3300 1075);
DISPLAY INVISIBLE (-3300 1075);
FORCEPROP 1 LAST COMMENT_BODY TRUE
J 2
(-2925 1100);
DISPLAY 1.170213 (-2925 1100);
PAINT GREEN (-2925 1100);
DISPLAY INVISIBLE (-2925 1100);
FORCEADD W_VCC_CIRCLE..1
(-4675 1300);
FORCEPROP 3 LASTPIN (-4675 1300) SIG_NAME P1V2_AUX_BMC\g
J 0
(-4665 1310);
DISPLAY 0.659574 (-4665 1310);
PAINT MONO (-4665 1310);
DISPLAY INVISIBLE (-4665 1310);
FORCEPROP 1 LAST HDL_POWER P1V2_AUX_BMC
J 1
(-4654 1375);
DISPLAY 0.872340 (-4654 1375);
PAINT ORANGE (-4654 1375);
FORCEPROP 1 LAST BODY_TYPE PLUMBING
J 0
(-4663 1294);
DISPLAY 0.340426 (-4663 1294);
PAINT GREEN (-4663 1294);
DISPLAY INVISIBLE (-4663 1294);
FORCEPROP 1 LAST CDS_LMAN_SYM_OUTLINE -100,100,100,-100
J 0
(-4675 1300);
DISPLAY 0.468085 (-4675 1300);
PAINT GREEN (-4675 1300);
DISPLAY INVISIBLE (-4675 1300);
FORCEPROP 2 LAST CDS_LIB w_power
J 0
(-4675 1300);
PAINT MONO (-4675 1300);
DISPLAY INVISIBLE (-4675 1300);
FORCEPROP 1 LAST PATH I119
J 0
(-4675 1300);
DISPLAY 0.617021 (-4675 1300);
PAINT GREEN (-4675 1300);
DISPLAY INVISIBLE (-4675 1300);
FORCEADD OFFPAGE..3
(-875 3600);
FORCEPROP 2 LAST $XR1 149 
J 0
(-541 3600);
DISPLAY 0.638298 (-541 3600);
PAINT MONO (-541 3600);
FORCEPROP 2 LAST $XR0 143 
J 0
(-661 3600);
DISPLAY 0.638298 (-661 3600);
PAINT MONO (-661 3600);
FORCEPROP 1 LAST COMMENT_BODY TRUE
J 0
(-925 3500);
DISPLAY 0.872340 (-925 3500);
PAINT GREEN (-925 3500);
DISPLAY INVISIBLE (-925 3500);
FORCEPROP 1 LAST OFFPAGE TRUE
J 0
(-550 3475);
DISPLAY 0.872340 (-550 3475);
PAINT GREEN (-550 3475);
DISPLAY INVISIBLE (-550 3475);
FORCEPROP 2 LAST CDS_LIB mstr_standard
J 0
(-875 3600);
PAINT MONO (-875 3600);
DISPLAY INVISIBLE (-875 3600);
FORCEPROP 2 LAST PATH I12
J 0
(-525 3650);
DISPLAY 1.021277 (-525 3650);
PAINT ORANGE (-525 3650);
DISPLAY INVISIBLE (-525 3650);
FORCEADD RES..2
R 2
(-4675 1100);
FORCEPROP 1 LAST MATERIAL CHIP
J 2
(-4715 1125);
DISPLAY 0.617021 (-4715 1125);
PAINT SKYBLUE (-4715 1125);
FORCEPROP 1 LAST TOLERANCE 1%
J 2
(-4720 1075);
DISPLAY 0.617021 (-4720 1075);
PAINT SKYBLUE (-4720 1075);
FORCEPROP 1 LAST PACK_TYPE 0402
J 2
(-4715 925);
DISPLAY 0.617021 (-4715 925);
PAINT SKYBLUE (-4715 925);
FORCEPROP 1 LAST PART_NUMBER G21796-072
J 2
(-4715 975);
DISPLAY 0.617021 (-4715 975);
PAINT BLUE (-4715 975);
FORCEPROP 1 LAST VALUE 4.75K
J 2
(-4720 1175);
DISPLAY 0.617021 (-4720 1175);
PAINT SKYBLUE (-4720 1175);
FORCEPROP 1 LAST LOCATION R25W119
J 2
(-4720 1225);
DISPLAY 0.617021 (-4720 1225);
PAINT AQUA (-4720 1225);
FORCEPROP 1 LAST WATTAGE 1/16W
J 2
(-4715 1025);
DISPLAY 0.617021 (-4715 1025);
PAINT SKYBLUE (-4715 1025);
FORCEPROP 2 LAST NO_XNET_CONNECTION 1
J 0
(-4725 1325);
PAINT MONO (-4725 1325);
DISPLAY INVISIBLE (-4725 1325);
FORCEPROP 2 LAST BOM_COST MIO_BIOS_MEM
J 0
(-4700 1325);
DISPLAY 1.021277 (-4700 1325);
PAINT ORANGE (-4700 1325);
DISPLAY INVISIBLE (-4700 1325);
FORCEPROP 2 LAST ROOM SB_SPI
J 0
(-4700 1275);
DISPLAY 1.021277 (-4700 1275);
PAINT ORANGE (-4700 1275);
DISPLAY INVISIBLE (-4700 1275);
FORCEPROP 2 LAST CDS_LIB mstr_discrete
J 0
(-4675 1100);
PAINT MONO (-4675 1100);
DISPLAY INVISIBLE (-4675 1100);
FORCEPROP 1 LAST PATH I120
J 2
(-4725 1275);
DISPLAY 0.978723 (-4725 1275);
PAINT WHITE (-4725 1275);
DISPLAY INVISIBLE (-4725 1275);
FORCEPROP 1 LASTPIN (-4675 1000) $PN 2
J 2
(-4680 1010);
DISPLAY 0.787234 (-4680 1010);
PAINT ORANGE (-4680 1010);
DISPLAY INVISIBLE (-4680 1010);
FORCEPROP 1 LASTPIN (-4675 1200) $PN 1
J 2
(-4680 1162);
DISPLAY 0.787234 (-4680 1162);
PAINT ORANGE (-4680 1162);
DISPLAY INVISIBLE (-4680 1162);
FORCEADD GND..1
(-4675 425);
FORCEPROP 3 LASTPIN (-4675 475) SIG_NAME GND\g
J 0
(-4665 485);
DISPLAY 0.659574 (-4665 485);
PAINT MONO (-4665 485);
DISPLAY INVISIBLE (-4665 485);
FORCEPROP 1 LAST HDL_POWER GND
J 0
(-4675 575);
DISPLAY 0.872340 (-4675 575);
PAINT GREEN (-4675 575);
DISPLAY INVISIBLE (-4675 575);
FORCEPROP 1 LAST BODY_TYPE PLUMBING
J 0
(-4720 382);
DISPLAY 0.340426 (-4720 382);
PAINT GREEN (-4720 382);
DISPLAY INVISIBLE (-4720 382);
FORCEPROP 2 LAST CDS_LIB mstr_symbols
J 0
(-4675 425);
PAINT MONO (-4675 425);
DISPLAY INVISIBLE (-4675 425);
FORCEPROP 1 LAST SIZE 1B
J 0
(-4600 375);
DISPLAY 0.872340 (-4600 375);
PAINT AQUA (-4600 375);
DISPLAY INVISIBLE (-4600 375);
FORCEPROP 1 LAST VOLTAGE 0.0V
J 0
(-4720 382);
DISPLAY 0.340426 (-4720 382);
PAINT GREEN (-4720 382);
DISPLAY INVISIBLE (-4720 382);
FORCEPROP 1 LAST PATH I121
J 0
(-4600 425);
DISPLAY 0.872340 (-4600 425);
PAINT AQUA (-4600 425);
DISPLAY INVISIBLE (-4600 425);
FORCEADD RES..2
R 2
(-4675 750);
FORCEPROP 1 LAST PART_NUMBER G21796-072
J 2
(-4715 625);
DISPLAY 0.617021 (-4715 625);
PAINT BLUE (-4715 625);
FORCEPROP 1 LAST WATTAGE 1/16W
J 2
(-4715 675);
DISPLAY 0.617021 (-4715 675);
PAINT SKYBLUE (-4715 675);
FORCEPROP 1 LAST MATERIAL EMPTY
J 2
(-4715 775);
DISPLAY 0.617021 (-4715 775);
PAINT RED (-4715 775);
FORCEPROP 1 LAST TOLERANCE 1%
J 2
(-4720 725);
DISPLAY 0.617021 (-4720 725);
PAINT SKYBLUE (-4720 725);
FORCEPROP 1 LAST VALUE 4.75K
J 2
(-4720 825);
DISPLAY 0.617021 (-4720 825);
PAINT SKYBLUE (-4720 825);
FORCEPROP 1 LAST PACK_TYPE 0402
J 2
(-4715 575);
DISPLAY 0.617021 (-4715 575);
PAINT SKYBLUE (-4715 575);
FORCEPROP 1 LAST LOCATION R25W118
J 2
(-4720 875);
DISPLAY 0.617021 (-4720 875);
PAINT AQUA (-4720 875);
FORCEPROP 2 LAST NO_XNET_CONNECTION 1
J 0
(-4725 975);
PAINT MONO (-4725 975);
DISPLAY INVISIBLE (-4725 975);
FORCEPROP 2 LAST BOM_COST MIO_BIOS_MEM
J 0
(-4700 975);
DISPLAY 1.021277 (-4700 975);
PAINT ORANGE (-4700 975);
DISPLAY INVISIBLE (-4700 975);
FORCEPROP 2 LAST ROOM SB_SPI
J 0
(-4700 925);
DISPLAY 1.021277 (-4700 925);
PAINT ORANGE (-4700 925);
DISPLAY INVISIBLE (-4700 925);
FORCEPROP 2 LAST CDS_LIB mstr_discrete
J 0
(-4675 750);
PAINT MONO (-4675 750);
DISPLAY INVISIBLE (-4675 750);
FORCEPROP 1 LAST PATH I122
J 2
(-4725 925);
DISPLAY 0.978723 (-4725 925);
PAINT WHITE (-4725 925);
DISPLAY INVISIBLE (-4725 925);
FORCEPROP 1 LASTPIN (-4675 650) $PN 2
J 2
(-4680 660);
DISPLAY 0.787234 (-4680 660);
PAINT ORANGE (-4680 660);
DISPLAY INVISIBLE (-4680 660);
FORCEPROP 1 LASTPIN (-4675 850) $PN 1
J 2
(-4680 812);
DISPLAY 0.787234 (-4680 812);
PAINT ORANGE (-4680 812);
DISPLAY INVISIBLE (-4680 812);
FORCEADD W_VCC_CIRCLE..1
(-6175 1375);
FORCEPROP 3 LASTPIN (-6175 1375) SIG_NAME P1V2_AUX_BMC\g
J 0
(-6165 1385);
DISPLAY 0.659574 (-6165 1385);
PAINT MONO (-6165 1385);
DISPLAY INVISIBLE (-6165 1385);
FORCEPROP 1 LAST HDL_POWER P1V2_AUX_BMC
J 1
(-6279 1450);
DISPLAY 0.872340 (-6279 1450);
PAINT ORANGE (-6279 1450);
FORCEPROP 1 LAST BODY_TYPE PLUMBING
J 0
(-6163 1369);
DISPLAY 0.340426 (-6163 1369);
PAINT GREEN (-6163 1369);
DISPLAY INVISIBLE (-6163 1369);
FORCEPROP 2 LAST CDS_LIB w_power
J 0
(-6175 1375);
PAINT MONO (-6175 1375);
DISPLAY INVISIBLE (-6175 1375);
FORCEPROP 1 LAST CDS_LMAN_SYM_OUTLINE -100,100,100,-100
J 0
(-6175 1375);
DISPLAY 0.468085 (-6175 1375);
PAINT GREEN (-6175 1375);
DISPLAY INVISIBLE (-6175 1375);
FORCEPROP 1 LAST PATH I123
J 0
(-6175 1375);
DISPLAY 0.617021 (-6175 1375);
PAINT GREEN (-6175 1375);
DISPLAY INVISIBLE (-6175 1375);
FORCEADD RES..2
(-6175 1050);
FORCEPROP 1 LASTPIN (-6175 950) $PN 2
J 0
(-6170 960);
DISPLAY 0.617021 (-6170 960);
PAINT ORANGE (-6170 960);
FORCEPROP 1 LASTPIN (-6175 1150) $PN 1
J 0
(-6170 1112);
DISPLAY 0.617021 (-6170 1112);
PAINT ORANGE (-6170 1112);
FORCEPROP 1 LAST VALUE 1.00K
J 0
(-6130 1125);
DISPLAY 0.617021 (-6130 1125);
PAINT SKYBLUE (-6130 1125);
FORCEPROP 1 LAST PACK_TYPE 0402
J 0
(-6135 875);
DISPLAY 0.617021 (-6135 875);
PAINT SKYBLUE (-6135 875);
FORCEPROP 1 LAST LOCATION R1T30
J 0
(-6130 1175);
DISPLAY 0.617021 (-6130 1175);
PAINT AQUA (-6130 1175);
FORCEPROP 1 LAST TOLERANCE 1%
J 0
(-6130 1075);
DISPLAY 0.617021 (-6130 1075);
PAINT SKYBLUE (-6130 1075);
FORCEPROP 1 LAST WATTAGE 1/16W
J 0
(-6135 1025);
DISPLAY 0.617021 (-6135 1025);
PAINT SKYBLUE (-6135 1025);
FORCEPROP 1 LAST MATERIAL CHIP
J 0
(-6135 975);
DISPLAY 0.617021 (-6135 975);
PAINT SKYBLUE (-6135 975);
FORCEPROP 1 LAST PART_NUMBER G21796-026
J 0
(-6135 925);
DISPLAY 0.617021 (-6135 925);
PAINT BLUE (-6135 925);
FORCEPROP 2 LAST SEC 1
J 0
(-6125 1275);
DISPLAY 0.680851 (-6125 1275);
PAINT MONO (-6125 1275);
DISPLAY INVISIBLE (-6125 1275);
FORCEPROP 2 LAST BOM_COST SM_MEM
J 0
(-6125 1275);
DISPLAY 1.021277 (-6125 1275);
PAINT ORANGE (-6125 1275);
DISPLAY INVISIBLE (-6125 1275);
FORCEPROP 2 LAST CDS_LIB mstr_discrete
J 0
(-6175 1050);
PAINT ORANGE (-6175 1050);
DISPLAY INVISIBLE (-6175 1050);
FORCEPROP 2 LAST SEC_TYPE 0402
J 0
(-6125 1275);
DISPLAY 1.021277 (-6125 1275);
PAINT ORANGE (-6125 1275);
DISPLAY INVISIBLE (-6125 1275);
FORCEPROP 2 LAST ROOM BMC_MEMORY
J 0
(-6125 1225);
DISPLAY 1.021277 (-6125 1225);
PAINT ORANGE (-6125 1225);
DISPLAY INVISIBLE (-6125 1225);
FORCEPROP 1 LAST PATH I124
J 0
(-6125 1225);
DISPLAY 0.978723 (-6125 1225);
PAINT WHITE (-6125 1225);
DISPLAY INVISIBLE (-6125 1225);
FORCEADD RES..2
(-6175 625);
FORCEPROP 1 LAST LOCATION R1T29
J 0
(-6130 750);
DISPLAY 0.617021 (-6130 750);
PAINT AQUA (-6130 750);
FORCEPROP 1 LAST PART_NUMBER G21796-026
J 0
(-6135 500);
DISPLAY 0.617021 (-6135 500);
PAINT BLUE (-6135 500);
FORCEPROP 1 LAST MATERIAL CHIP
J 0
(-6135 550);
DISPLAY 0.617021 (-6135 550);
PAINT SKYBLUE (-6135 550);
FORCEPROP 1 LAST WATTAGE 1/16W
J 0
(-6135 600);
DISPLAY 0.617021 (-6135 600);
PAINT SKYBLUE (-6135 600);
FORCEPROP 1 LASTPIN (-6175 525) $PN 2
J 0
(-6170 535);
DISPLAY 0.617021 (-6170 535);
PAINT ORANGE (-6170 535);
FORCEPROP 1 LAST PACK_TYPE 0402
J 0
(-6135 450);
DISPLAY 0.617021 (-6135 450);
PAINT SKYBLUE (-6135 450);
FORCEPROP 1 LAST VALUE 1.00K
J 0
(-6130 700);
DISPLAY 0.617021 (-6130 700);
PAINT SKYBLUE (-6130 700);
FORCEPROP 1 LAST TOLERANCE 1%
J 0
(-6130 650);
DISPLAY 0.617021 (-6130 650);
PAINT SKYBLUE (-6130 650);
FORCEPROP 1 LASTPIN (-6175 725) $PN 1
J 0
(-6170 687);
DISPLAY 0.617021 (-6170 687);
PAINT ORANGE (-6170 687);
FORCEPROP 2 LAST SEC 1
J 0
(-6125 850);
DISPLAY 0.680851 (-6125 850);
PAINT MONO (-6125 850);
DISPLAY INVISIBLE (-6125 850);
FORCEPROP 2 LAST BOM_COST SM_MEM
J 0
(-6125 850);
DISPLAY 1.021277 (-6125 850);
PAINT ORANGE (-6125 850);
DISPLAY INVISIBLE (-6125 850);
FORCEPROP 2 LAST CDS_LIB mstr_discrete
J 0
(-6175 625);
PAINT ORANGE (-6175 625);
DISPLAY INVISIBLE (-6175 625);
FORCEPROP 2 LAST SEC_TYPE 0402
J 0
(-6125 850);
DISPLAY 1.021277 (-6125 850);
PAINT ORANGE (-6125 850);
DISPLAY INVISIBLE (-6125 850);
FORCEPROP 2 LAST ROOM BMC_MEMORY
J 0
(-6125 800);
DISPLAY 1.021277 (-6125 800);
PAINT ORANGE (-6125 800);
DISPLAY INVISIBLE (-6125 800);
FORCEPROP 1 LAST PATH I125
J 0
(-6125 800);
DISPLAY 0.978723 (-6125 800);
PAINT WHITE (-6125 800);
DISPLAY INVISIBLE (-6125 800);
FORCEADD CAP..1
(-6450 625);
FORCEPROP 1 LAST LOCATION C25W12
J 0
(-6400 725);
DISPLAY 0.617021 (-6400 725);
PAINT AQUA (-6400 725);
FORCEPROP 1 LAST VALUE 1.0UF
J 0
(-6400 675);
DISPLAY 0.617021 (-6400 675);
PAINT SKYBLUE (-6400 675);
FORCEPROP 1 LAST PACK_TYPE 0402
J 0
(-6400 425);
DISPLAY 0.617021 (-6400 425);
PAINT SKYBLUE (-6400 425);
FORCEPROP 1 LAST PART_NUMBER D97712-004
J 0
(-6400 475);
DISPLAY 0.617021 (-6400 475);
PAINT BLUE (-6400 475);
FORCEPROP 1 LAST TOLERANCE 10%
J 0
(-6400 575);
DISPLAY 0.617021 (-6400 575);
PAINT SKYBLUE (-6400 575);
FORCEPROP 1 LASTPIN (-6450 525) $PN 2
J 0
(-6440 505);
DISPLAY 0.617021 (-6440 505);
PAINT ORANGE (-6440 505);
FORCEPROP 1 LASTPIN (-6450 725) $PN 1
J 0
(-6440 705);
DISPLAY 0.617021 (-6440 705);
PAINT ORANGE (-6440 705);
FORCEPROP 1 LAST MATERIAL X6S
J 0
(-6400 525);
DISPLAY 0.617021 (-6400 525);
PAINT SKYBLUE (-6400 525);
FORCEPROP 1 LAST VOLTAGE 6.3V
J 0
(-6400 625);
DISPLAY 0.617021 (-6400 625);
PAINT SKYBLUE (-6400 625);
FORCEPROP 0 LAST CDS_SEC 1
J 0
(-6400 775);
PAINT MONO (-6400 775);
DISPLAY INVISIBLE (-6400 775);
FORCEPROP 2 LAST SEC 1
J 0
(-6400 825);
DISPLAY 0.680851 (-6400 825);
PAINT MONO (-6400 825);
DISPLAY INVISIBLE (-6400 825);
FORCEPROP 2 LAST BOM_COST SM_MEM
J 0
(-6400 825);
DISPLAY 1.021277 (-6400 825);
PAINT ORANGE (-6400 825);
DISPLAY INVISIBLE (-6400 825);
FORCEPROP 2 LAST CDS_LIB mstr_discrete
J 0
(-6450 625);
PAINT ORANGE (-6450 625);
DISPLAY INVISIBLE (-6450 625);
FORCEPROP 2 LAST SEC_TYPE 0402
J 0
(-6400 825);
DISPLAY 1.021277 (-6400 825);
PAINT ORANGE (-6400 825);
DISPLAY INVISIBLE (-6400 825);
FORCEPROP 2 LAST ROOM BMC_MEMORY
J 0
(-6400 775);
DISPLAY 1.021277 (-6400 775);
PAINT ORANGE (-6400 775);
DISPLAY INVISIBLE (-6400 775);
FORCEPROP 1 LAST PATH I126
J 0
(-6400 775);
DISPLAY 0.978723 (-6400 775);
PAINT WHITE (-6400 775);
DISPLAY INVISIBLE (-6400 775);
FORCEPROP 0 LAST CDS_LOCATION C25W12
J 0
(-6400 775);
PAINT MONO (-6400 775);
DISPLAY INVISIBLE (-6400 775);
FORCEADD GND..1
(-6175 175);
FORCEPROP 3 LASTPIN (-6175 225) SIG_NAME GND\g
J 0
(-6165 235);
DISPLAY 0.659574 (-6165 235);
PAINT MONO (-6165 235);
DISPLAY INVISIBLE (-6165 235);
FORCEPROP 1 LAST HDL_POWER GND
J 0
(-6175 325);
DISPLAY 0.872340 (-6175 325);
PAINT GREEN (-6175 325);
DISPLAY INVISIBLE (-6175 325);
FORCEPROP 1 LAST BODY_TYPE PLUMBING
J 0
(-6220 132);
DISPLAY 0.340426 (-6220 132);
PAINT GREEN (-6220 132);
DISPLAY INVISIBLE (-6220 132);
FORCEPROP 1 LAST VOLTAGE 0.0V
J 0
(-6220 132);
DISPLAY 0.340426 (-6220 132);
PAINT GREEN (-6220 132);
DISPLAY INVISIBLE (-6220 132);
FORCEPROP 1 LAST SIZE 1B
J 0
(-6100 125);
DISPLAY 0.872340 (-6100 125);
PAINT AQUA (-6100 125);
DISPLAY INVISIBLE (-6100 125);
FORCEPROP 2 LAST CDS_LIB mstr_symbols
J 0
(-6175 175);
PAINT ORANGE (-6175 175);
DISPLAY INVISIBLE (-6175 175);
FORCEPROP 1 LAST PATH I127
J 0
(-6100 175);
DISPLAY 0.872340 (-6100 175);
PAINT AQUA (-6100 175);
DISPLAY INVISIBLE (-6100 175);
FORCEADD OFFPAGE..3
(-875 3700);
FORCEPROP 2 LAST $XR0 143 
J 0
(-661 3700);
DISPLAY 0.638298 (-661 3700);
PAINT MONO (-661 3700);
FORCEPROP 2 LAST $XR1 149 
J 0
(-541 3700);
DISPLAY 0.638298 (-541 3700);
PAINT MONO (-541 3700);
FORCEPROP 1 LAST COMMENT_BODY TRUE
J 0
(-925 3600);
DISPLAY 0.872340 (-925 3600);
PAINT GREEN (-925 3600);
DISPLAY INVISIBLE (-925 3600);
FORCEPROP 1 LAST OFFPAGE TRUE
J 0
(-550 3575);
DISPLAY 0.872340 (-550 3575);
PAINT GREEN (-550 3575);
DISPLAY INVISIBLE (-550 3575);
FORCEPROP 2 LAST CDS_LIB mstr_standard
J 0
(-875 3700);
PAINT MONO (-875 3700);
DISPLAY INVISIBLE (-875 3700);
FORCEPROP 2 LAST PATH I13
J 0
(-525 3750);
DISPLAY 1.021277 (-525 3750);
PAINT ORANGE (-525 3750);
DISPLAY INVISIBLE (-525 3750);
FORCEADD RES..1
(-1375 4600);
FORCEPROP 1 LAST PACK_TYPE 0402
J 0
(-1125 4450);
DISPLAY 0.617021 (-1125 4450);
PAINT SKYBLUE (-1125 4450);
FORCEPROP 1 LAST VALUE 33.2
J 2
(-1400 4500);
DISPLAY 0.617021 (-1400 4500);
PAINT SKYBLUE (-1400 4500);
FORCEPROP 1 LAST MATERIAL CHIP
J 0
(-1375 4450);
DISPLAY 0.617021 (-1375 4450);
PAINT SKYBLUE (-1375 4450);
FORCEPROP 1 LAST WATTAGE 1/16W
J 2
(-1400 4450);
DISPLAY 0.617021 (-1400 4450);
PAINT SKYBLUE (-1400 4450);
FORCEPROP 1 LASTPIN (-1275 4600) $PN 2
J 0
(-1313 4612);
DISPLAY 0.617021 (-1313 4612);
PAINT ORANGE (-1313 4612);
FORCEPROP 1 LASTPIN (-1475 4600) $PN 1
J 0
(-1463 4612);
DISPLAY 0.617021 (-1463 4612);
PAINT ORANGE (-1463 4612);
FORCEPROP 1 LAST TOLERANCE 1%
J 0
(-1375 4500);
DISPLAY 0.617021 (-1375 4500);
PAINT SKYBLUE (-1375 4500);
FORCEPROP 1 LAST LOCATION R9F34
J 0
(-1425 4650);
DISPLAY 0.617021 (-1425 4650);
PAINT AQUA (-1425 4650);
FORCEPROP 1 LAST PART_NUMBER G21796-074
J 0
(-1425 4700);
DISPLAY 0.617021 (-1425 4700);
PAINT BLUE (-1425 4700);
FORCEPROP 2 LAST SEC_TYPE 0402
J 0
(-1425 4800);
DISPLAY 1.021277 (-1425 4800);
PAINT ORANGE (-1425 4800);
DISPLAY INVISIBLE (-1425 4800);
FORCEPROP 2 LAST CDS_LIB mstr_discrete
J 0
(-1375 4600);
PAINT MONO (-1375 4600);
DISPLAY INVISIBLE (-1375 4600);
FORCEPROP 2 LAST BOM_COST SM_MEM
J 0
(-1425 4800);
DISPLAY 1.021277 (-1425 4800);
PAINT ORANGE (-1425 4800);
DISPLAY INVISIBLE (-1425 4800);
FORCEPROP 2 LAST SEC 1
J 0
(-1425 4800);
DISPLAY 0.680851 (-1425 4800);
PAINT MONO (-1425 4800);
DISPLAY INVISIBLE (-1425 4800);
FORCEPROP 2 LAST CDS_LOCATION R9F34
J 0
(-1425 4650);
DISPLAY 0.617021 (-1425 4650);
PAINT AQUA (-1425 4650);
DISPLAY INVISIBLE (-1425 4650);
FORCEPROP 2 LAST ROOM BMC_MEMORY
J 0
(-1425 4750);
DISPLAY 1.021277 (-1425 4750);
PAINT ORANGE (-1425 4750);
DISPLAY INVISIBLE (-1425 4750);
FORCEPROP 0 LAST CDS_SEC 1
J 0
(-1425 4750);
PAINT MONO (-1425 4750);
DISPLAY INVISIBLE (-1425 4750);
FORCEPROP 1 LAST PATH I14
J 0
(-1425 4750);
DISPLAY 0.978723 (-1425 4750);
PAINT WHITE (-1425 4750);
DISPLAY INVISIBLE (-1425 4750);
FORCEADD W_VCC_CIRCLE..1
(-1725 4925);
FORCEPROP 3 LASTPIN (-1725 4925) SIG_NAME P1V2_AUX_BMC\g
J 0
(-1715 4935);
DISPLAY 0.659574 (-1715 4935);
PAINT MONO (-1715 4935);
DISPLAY INVISIBLE (-1715 4935);
FORCEPROP 1 LAST HDL_POWER P1V2_AUX_BMC
J 1
(-1704 5000);
DISPLAY 0.872340 (-1704 5000);
PAINT ORANGE (-1704 5000);
FORCEPROP 1 LAST BODY_TYPE PLUMBING
J 0
(-1713 4919);
DISPLAY 0.340426 (-1713 4919);
PAINT GREEN (-1713 4919);
DISPLAY INVISIBLE (-1713 4919);
FORCEPROP 1 LAST CDS_LMAN_SYM_OUTLINE -100,100,100,-100
J 0
(-1725 4925);
DISPLAY 0.468085 (-1725 4925);
PAINT GREEN (-1725 4925);
DISPLAY INVISIBLE (-1725 4925);
FORCEPROP 2 LAST CDS_LIB w_power
J 0
(-1725 4925);
PAINT MONO (-1725 4925);
DISPLAY INVISIBLE (-1725 4925);
FORCEPROP 1 LAST PATH I15
J 0
(-1725 4925);
DISPLAY 0.617021 (-1725 4925);
PAINT GREEN (-1725 4925);
DISPLAY INVISIBLE (-1725 4925);
FORCEADD GND..1
(-7900 2750);
FORCEPROP 3 LASTPIN (-7900 2800) SIG_NAME GND\g
J 0
(-7890 2810);
DISPLAY 0.659574 (-7890 2810);
PAINT MONO (-7890 2810);
DISPLAY INVISIBLE (-7890 2810);
FORCEPROP 2 LAST CDS_LIB mstr_symbols
J 0
(-7900 2750);
PAINT MONO (-7900 2750);
DISPLAY INVISIBLE (-7900 2750);
FORCEPROP 1 LAST VOLTAGE 0.0V
J 0
(-7945 2707);
DISPLAY 0.340426 (-7945 2707);
PAINT GREEN (-7945 2707);
DISPLAY INVISIBLE (-7945 2707);
FORCEPROP 1 LAST SIZE 1B
J 0
(-7825 2700);
DISPLAY 0.872340 (-7825 2700);
PAINT AQUA (-7825 2700);
DISPLAY INVISIBLE (-7825 2700);
FORCEPROP 1 LAST PATH I154
J 0
(-7825 2750);
DISPLAY 0.872340 (-7825 2750);
PAINT AQUA (-7825 2750);
DISPLAY INVISIBLE (-7825 2750);
FORCEPROP 1 LAST BODY_TYPE PLUMBING
J 0
(-7945 2707);
DISPLAY 0.340426 (-7945 2707);
PAINT GREEN (-7945 2707);
DISPLAY INVISIBLE (-7945 2707);
FORCEPROP 1 LAST HDL_POWER GND
J 0
(-7900 2900);
DISPLAY 0.872340 (-7900 2900);
PAINT GREEN (-7900 2900);
DISPLAY INVISIBLE (-7900 2900);
FORCEADD P3V3_STBY..1
(-6675 2400);
FORCEPROP 3 LASTPIN (-6675 2350) SIG_NAME P3V3_STBY\g
J 0
(-6665 2360);
DISPLAY 0.659574 (-6665 2360);
PAINT MONO (-6665 2360);
DISPLAY INVISIBLE (-6665 2360);
FORCEPROP 1 LAST HDL_POWER P3V3_STBY
J 0
(-6975 2275);
DISPLAY 0.872340 (-6975 2275);
PAINT ORANGE (-6975 2275);
DISPLAY INVISIBLE (-6975 2275);
FORCEPROP 1 LAST BODY_TYPE PLUMBING
J 0
(-6720 2357);
DISPLAY 0.340426 (-6720 2357);
PAINT GREEN (-6720 2357);
DISPLAY INVISIBLE (-6720 2357);
FORCEPROP 1 LAST VOLTAGE 3.3V
J 0
(-6720 2357);
DISPLAY 0.340426 (-6720 2357);
PAINT SKYBLUE (-6720 2357);
DISPLAY INVISIBLE (-6720 2357);
FORCEPROP 2 LAST CDS_LIB mstr_symbols
J 0
(-6675 2400);
PAINT MONO (-6675 2400);
DISPLAY INVISIBLE (-6675 2400);
FORCEPROP 1 LAST SIZE 1B
J 0
(-6630 2422);
DISPLAY 0.340426 (-6630 2422);
PAINT GREEN (-6630 2422);
DISPLAY INVISIBLE (-6630 2422);
FORCEPROP 1 LAST PATH I155
J 0
(-6630 2402);
DISPLAY 0.340426 (-6630 2402);
PAINT GREEN (-6630 2402);
DISPLAY INVISIBLE (-6630 2402);
FORCEADD RES..2
(-6675 2150);
FORCEPROP 1 LAST LOCATION R8B25
J 0
(-6630 2275);
DISPLAY 0.617021 (-6630 2275);
PAINT AQUA (-6630 2275);
FORCEPROP 1 LASTPIN (-6675 2250) $PN 1
J 0
(-6670 2212);
DISPLAY 0.617021 (-6670 2212);
PAINT ORANGE (-6670 2212);
FORCEPROP 1 LAST MATERIAL CHIP
J 0
(-6635 2075);
DISPLAY 0.617021 (-6635 2075);
PAINT SKYBLUE (-6635 2075);
FORCEPROP 1 LAST TOLERANCE 1%
J 0
(-6630 2175);
DISPLAY 0.617021 (-6630 2175);
PAINT SKYBLUE (-6630 2175);
FORCEPROP 1 LAST PACK_TYPE 0402
J 0
(-6635 1975);
DISPLAY 0.617021 (-6635 1975);
PAINT SKYBLUE (-6635 1975);
FORCEPROP 1 LAST PART_NUMBER G21796-072
J 0
(-6635 2025);
DISPLAY 0.617021 (-6635 2025);
PAINT BLUE (-6635 2025);
FORCEPROP 1 LASTPIN (-6675 2050) $PN 2
J 0
(-6670 2060);
DISPLAY 0.617021 (-6670 2060);
PAINT ORANGE (-6670 2060);
FORCEPROP 1 LAST WATTAGE 1/16W
J 0
(-6635 2125);
DISPLAY 0.617021 (-6635 2125);
PAINT SKYBLUE (-6635 2125);
FORCEPROP 1 LAST VALUE 4.75K
J 0
(-6630 2225);
DISPLAY 0.617021 (-6630 2225);
PAINT SKYBLUE (-6630 2225);
FORCEPROP 0 LAST CDS_SEC 1
J 0
(-6625 2325);
PAINT MONO (-6625 2325);
DISPLAY INVISIBLE (-6625 2325);
FORCEPROP 2 LAST CDS_LIB mstr_discrete
J 0
(-6675 2150);
PAINT MONO (-6675 2150);
DISPLAY INVISIBLE (-6675 2150);
FORCEPROP 0 LAST BOM_COST SM_CONTROLLER
J 0
(-6625 2475);
DISPLAY 1.021277 (-6625 2475);
PAINT ORANGE (-6625 2475);
DISPLAY INVISIBLE (-6625 2475);
FORCEPROP 2 LAST SEC_TYPE 0402
J 0
(-6625 2375);
DISPLAY 1.021277 (-6625 2375);
PAINT ORANGE (-6625 2375);
DISPLAY INVISIBLE (-6625 2375);
FORCEPROP 2 LAST SEC 1
J 0
(-6625 2375);
DISPLAY 0.680851 (-6625 2375);
PAINT MONO (-6625 2375);
DISPLAY INVISIBLE (-6625 2375);
FORCEPROP 2 LAST CDS_LOCATION R8B25
J 0
(-6630 2275);
DISPLAY 0.617021 (-6630 2275);
PAINT AQUA (-6630 2275);
DISPLAY INVISIBLE (-6630 2275);
FORCEPROP 0 LAST ROOM BMC
J 0
(-6625 2375);
DISPLAY 1.021277 (-6625 2375);
PAINT ORANGE (-6625 2375);
DISPLAY INVISIBLE (-6625 2375);
FORCEPROP 1 LAST PATH I156
J 0
(-6625 2325);
DISPLAY 0.978723 (-6625 2325);
PAINT WHITE (-6625 2325);
DISPLAY INVISIBLE (-6625 2325);
FORCEADD OFFPAGE..1
(-7225 1725);
FORCEPROP 2 LAST $XR0 119 
J 0
(-7507 1725);
DISPLAY 0.638298 (-7507 1725);
PAINT MONO (-7507 1725);
FORCEPROP 2 LAST $XR1 145 
J 0
(-7627 1725);
DISPLAY 0.638298 (-7627 1725);
PAINT MONO (-7627 1725);
FORCEPROP 1 LAST COMMENT_BODY TRUE
J 0
(-7100 1625);
DISPLAY 0.872340 (-7100 1625);
PAINT GREEN (-7100 1625);
DISPLAY INVISIBLE (-7100 1625);
FORCEPROP 1 LAST OFFPAGE TRUE
J 0
(-6900 1600);
DISPLAY 0.872340 (-6900 1600);
PAINT GREEN (-6900 1600);
DISPLAY INVISIBLE (-6900 1600);
FORCEPROP 2 LAST CDS_LIB mstr_standard
J 0
(-7225 1725);
PAINT MONO (-7225 1725);
DISPLAY INVISIBLE (-7225 1725);
FORCEPROP 2 LAST PATH I157
J 0
(-7500 1775);
DISPLAY 1.021277 (-7500 1775);
PAINT ORANGE (-7500 1775);
DISPLAY INVISIBLE (-7500 1775);
FORCEADD CAP..1
(-6775 1025);
FORCEPROP 1 LAST VALUE 0.01UF
J 0
(-6725 1075);
DISPLAY 0.617021 (-6725 1075);
PAINT SKYBLUE (-6725 1075);
FORCEPROP 1 LAST PACK_TYPE 0402LF
J 0
(-6725 825);
DISPLAY 0.617021 (-6725 825);
PAINT SKYBLUE (-6725 825);
FORCEPROP 1 LAST MATERIAL X7R
J 0
(-6725 925);
DISPLAY 0.617021 (-6725 925);
PAINT SKYBLUE (-6725 925);
FORCEPROP 1 LASTPIN (-6775 1125) $PN 1
J 0
(-6765 1105);
DISPLAY 0.617021 (-6765 1105);
PAINT ORANGE (-6765 1105);
FORCEPROP 1 LAST VOLTAGE 25V
J 0
(-6725 1025);
DISPLAY 0.617021 (-6725 1025);
PAINT SKYBLUE (-6725 1025);
FORCEPROP 1 LAST TOLERANCE 10%
J 0
(-6725 975);
DISPLAY 0.617021 (-6725 975);
PAINT SKYBLUE (-6725 975);
FORCEPROP 1 LAST LOCATION C25W10
J 0
(-6725 1125);
DISPLAY 0.617021 (-6725 1125);
PAINT AQUA (-6725 1125);
FORCEPROP 1 LASTPIN (-6775 925) $PN 2
J 0
(-6765 905);
DISPLAY 0.617021 (-6765 905);
PAINT ORANGE (-6765 905);
FORCEPROP 1 LAST PART_NUMBER A36096-045
J 0
(-6725 875);
DISPLAY 0.617021 (-6725 875);
PAINT BLUE (-6725 875);
FORCEPROP 2 LAST ROOM BMC_MEMORY
J 0
(-6725 1175);
DISPLAY 1.021277 (-6725 1175);
PAINT ORANGE (-6725 1175);
DISPLAY INVISIBLE (-6725 1175);
FORCEPROP 2 LAST SEC_TYPE 0402LF
J 0
(-6725 1225);
DISPLAY 1.021277 (-6725 1225);
PAINT ORANGE (-6725 1225);
DISPLAY INVISIBLE (-6725 1225);
FORCEPROP 2 LAST CDS_LIB mstr_discrete
J 0
(-6775 1025);
PAINT ORANGE (-6775 1025);
DISPLAY INVISIBLE (-6775 1025);
FORCEPROP 2 LAST BOM_COST SM_MEM
J 0
(-6725 1225);
DISPLAY 1.021277 (-6725 1225);
PAINT ORANGE (-6725 1225);
DISPLAY INVISIBLE (-6725 1225);
FORCEPROP 2 LAST SEC 1
J 0
(-6725 1225);
DISPLAY 0.680851 (-6725 1225);
PAINT MONO (-6725 1225);
DISPLAY INVISIBLE (-6725 1225);
FORCEPROP 0 LAST CDS_SEC 1
J 0
(-6725 1175);
PAINT MONO (-6725 1175);
DISPLAY INVISIBLE (-6725 1175);
FORCEPROP 1 LAST PATH I158
J 0
(-6725 1175);
DISPLAY 0.978723 (-6725 1175);
PAINT WHITE (-6725 1175);
DISPLAY INVISIBLE (-6725 1175);
FORCEPROP 0 LAST CDS_LOCATION C25W10
J 0
(-6725 1175);
PAINT MONO (-6725 1175);
DISPLAY INVISIBLE (-6725 1175);
FORCEADD CAP..1
(-6775 625);
FORCEPROP 1 LAST TOLERANCE 10%
J 0
(-6725 575);
DISPLAY 0.617021 (-6725 575);
PAINT SKYBLUE (-6725 575);
FORCEPROP 1 LAST PART_NUMBER A36096-045
J 0
(-6725 475);
DISPLAY 0.617021 (-6725 475);
PAINT BLUE (-6725 475);
FORCEPROP 1 LAST VALUE 0.01UF
J 0
(-6725 675);
DISPLAY 0.617021 (-6725 675);
PAINT SKYBLUE (-6725 675);
FORCEPROP 1 LAST PACK_TYPE 0402LF
J 0
(-6725 425);
DISPLAY 0.617021 (-6725 425);
PAINT SKYBLUE (-6725 425);
FORCEPROP 1 LAST MATERIAL X7R
J 0
(-6725 525);
DISPLAY 0.617021 (-6725 525);
PAINT SKYBLUE (-6725 525);
FORCEPROP 1 LASTPIN (-6775 725) $PN 1
J 0
(-6765 705);
DISPLAY 0.617021 (-6765 705);
PAINT ORANGE (-6765 705);
FORCEPROP 1 LASTPIN (-6775 525) $PN 2
J 0
(-6765 505);
DISPLAY 0.617021 (-6765 505);
PAINT ORANGE (-6765 505);
FORCEPROP 1 LAST VOLTAGE 25V
J 0
(-6725 625);
DISPLAY 0.617021 (-6725 625);
PAINT SKYBLUE (-6725 625);
FORCEPROP 1 LAST LOCATION C25W11
J 0
(-6725 725);
DISPLAY 0.617021 (-6725 725);
PAINT AQUA (-6725 725);
FORCEPROP 2 LAST ROOM BMC_MEMORY
J 0
(-6725 775);
DISPLAY 1.021277 (-6725 775);
PAINT ORANGE (-6725 775);
DISPLAY INVISIBLE (-6725 775);
FORCEPROP 2 LAST SEC_TYPE 0402LF
J 0
(-6725 825);
DISPLAY 1.021277 (-6725 825);
PAINT ORANGE (-6725 825);
DISPLAY INVISIBLE (-6725 825);
FORCEPROP 2 LAST CDS_LIB mstr_discrete
J 0
(-6775 625);
PAINT ORANGE (-6775 625);
DISPLAY INVISIBLE (-6775 625);
FORCEPROP 2 LAST BOM_COST SM_MEM
J 0
(-6725 825);
DISPLAY 1.021277 (-6725 825);
PAINT ORANGE (-6725 825);
DISPLAY INVISIBLE (-6725 825);
FORCEPROP 2 LAST SEC 1
J 0
(-6725 825);
DISPLAY 0.680851 (-6725 825);
PAINT MONO (-6725 825);
DISPLAY INVISIBLE (-6725 825);
FORCEPROP 0 LAST CDS_SEC 1
J 0
(-6725 775);
PAINT MONO (-6725 775);
DISPLAY INVISIBLE (-6725 775);
FORCEPROP 1 LAST PATH I159
J 0
(-6725 775);
DISPLAY 0.978723 (-6725 775);
PAINT WHITE (-6725 775);
DISPLAY INVISIBLE (-6725 775);
FORCEPROP 0 LAST CDS_LOCATION C25W11
J 0
(-6725 775);
PAINT MONO (-6725 775);
DISPLAY INVISIBLE (-6725 775);
FORCEADD RES..2
(-1725 4775);
FORCEPROP 1 LASTPIN (-1725 4875) $PN 1
J 0
(-1720 4837);
DISPLAY 0.617021 (-1720 4837);
PAINT ORANGE (-1720 4837);
FORCEPROP 1 LASTPIN (-1725 4675) $PN 2
J 0
(-1720 4685);
DISPLAY 0.617021 (-1720 4685);
PAINT ORANGE (-1720 4685);
FORCEPROP 1 LAST TOLERANCE 1%
J 0
(-1680 4800);
DISPLAY 0.617021 (-1680 4800);
PAINT SKYBLUE (-1680 4800);
FORCEPROP 1 LAST PACK_TYPE 0402
J 0
(-1685 4600);
DISPLAY 0.617021 (-1685 4600);
PAINT SKYBLUE (-1685 4600);
FORCEPROP 1 LAST PART_NUMBER G21796-072
J 0
(-1685 4650);
DISPLAY 0.617021 (-1685 4650);
PAINT BLUE (-1685 4650);
FORCEPROP 1 LAST WATTAGE 1/16W
J 0
(-1685 4750);
DISPLAY 0.617021 (-1685 4750);
PAINT SKYBLUE (-1685 4750);
FORCEPROP 1 LAST LOCATION R9F29
J 0
(-1680 4900);
DISPLAY 0.617021 (-1680 4900);
PAINT AQUA (-1680 4900);
FORCEPROP 1 LAST MATERIAL CHIP
J 0
(-1685 4700);
DISPLAY 0.617021 (-1685 4700);
PAINT SKYBLUE (-1685 4700);
FORCEPROP 1 LAST VALUE 4.75K
J 0
(-1680 4850);
DISPLAY 0.617021 (-1680 4850);
PAINT SKYBLUE (-1680 4850);
FORCEPROP 0 LAST CDS_SEC 1
J 0
(-1675 4950);
PAINT MONO (-1675 4950);
DISPLAY INVISIBLE (-1675 4950);
FORCEPROP 2 LAST ROOM BMC_MEMORY
J 0
(-1675 4950);
DISPLAY 1.021277 (-1675 4950);
PAINT ORANGE (-1675 4950);
DISPLAY INVISIBLE (-1675 4950);
FORCEPROP 2 LAST CDS_LOCATION R9F29
J 0
(-1680 4900);
DISPLAY 0.617021 (-1680 4900);
PAINT AQUA (-1680 4900);
DISPLAY INVISIBLE (-1680 4900);
FORCEPROP 2 LAST SEC 1
J 0
(-1675 5000);
DISPLAY 0.680851 (-1675 5000);
PAINT MONO (-1675 5000);
DISPLAY INVISIBLE (-1675 5000);
FORCEPROP 2 LAST BOM_COST SM_MEM
J 0
(-1675 5000);
DISPLAY 1.021277 (-1675 5000);
PAINT ORANGE (-1675 5000);
DISPLAY INVISIBLE (-1675 5000);
FORCEPROP 2 LAST CDS_LIB mstr_discrete
J 0
(-1725 4775);
PAINT ORANGE (-1725 4775);
DISPLAY INVISIBLE (-1725 4775);
FORCEPROP 2 LAST SEC_TYPE 0402
J 0
(-1675 5000);
DISPLAY 1.021277 (-1675 5000);
PAINT ORANGE (-1675 5000);
DISPLAY INVISIBLE (-1675 5000);
FORCEPROP 1 LAST PATH I16
J 0
(-1675 4950);
DISPLAY 0.978723 (-1675 4950);
PAINT WHITE (-1675 4950);
DISPLAY INVISIBLE (-1675 4950);
FORCEADD 120R2F-GP..1
R 1
(-7525 4300);
FORCEPROP 1 LAST LOCATION R25W1
J 0
(-7875 4300);
DISPLAY 0.617021 (-7875 4300);
PAINT GREEN (-7875 4300);
FORCEPROP 1 LAST VALUE 120R2F-GP
J 0
(-7325 4300);
DISPLAY 0.617021 (-7325 4300);
PAINT GREEN (-7325 4300);
FORCEPROP 1 LAST PATH I160
R 1
J 0
(-7525 4300);
DISPLAY 0.617021 (-7525 4300);
PAINT GREEN (-7525 4300);
DISPLAY INVISIBLE (-7525 4300);
FORCEPROP 1 LAST PACK_TYPE RCL_GP
R 1
J 0
(-7525 4300);
DISPLAY 0.617021 (-7525 4300);
PAINT GREEN (-7525 4300);
DISPLAY INVISIBLE (-7525 4300);
FORCEPROP 1 LAST PART_NUMBER 64.12005.6DL
R 1
J 0
(-7525 4300);
DISPLAY 0.617021 (-7525 4300);
PAINT GREEN (-7525 4300);
DISPLAY INVISIBLE (-7525 4300);
FORCEPROP 2 LAST CDS_LIB w_hdl
R 1
J 0
(-7525 4300);
PAINT MONO (-7525 4300);
DISPLAY INVISIBLE (-7525 4300);
FORCEPROP 1 LAST CDS_LMAN_SYM_OUTLINE -50,75,50,-75
R 1
J 0
(-7525 4300);
DISPLAY 0.468085 (-7525 4300);
PAINT GREEN (-7525 4300);
DISPLAY INVISIBLE (-7525 4300);
FORCEADD 120R2F-GP..1
R 1
(-7525 4250);
FORCEPROP 1 LAST LOCATION R25W2
J 0
(-7875 4250);
DISPLAY 0.617021 (-7875 4250);
PAINT GREEN (-7875 4250);
FORCEPROP 1 LAST VALUE 120R2F-GP
J 0
(-7325 4250);
DISPLAY 0.617021 (-7325 4250);
PAINT GREEN (-7325 4250);
FORCEPROP 1 LAST PATH I161
R 1
J 0
(-7525 4250);
DISPLAY 0.617021 (-7525 4250);
PAINT GREEN (-7525 4250);
DISPLAY INVISIBLE (-7525 4250);
FORCEPROP 1 LAST PACK_TYPE RCL_GP
R 1
J 0
(-7525 4250);
DISPLAY 0.617021 (-7525 4250);
PAINT GREEN (-7525 4250);
DISPLAY INVISIBLE (-7525 4250);
FORCEPROP 1 LAST PART_NUMBER 64.12005.6DL
R 1
J 0
(-7525 4250);
DISPLAY 0.617021 (-7525 4250);
PAINT GREEN (-7525 4250);
DISPLAY INVISIBLE (-7525 4250);
FORCEPROP 1 LAST CDS_LMAN_SYM_OUTLINE -50,75,50,-75
R 1
J 0
(-7525 4250);
DISPLAY 0.468085 (-7525 4250);
PAINT GREEN (-7525 4250);
DISPLAY INVISIBLE (-7525 4250);
FORCEPROP 2 LAST CDS_LIB w_hdl
J 0
(-7525 4250);
PAINT MONO (-7525 4250);
DISPLAY INVISIBLE (-7525 4250);
FORCEADD 120R2F-GP..1
R 1
(-7525 4150);
FORCEPROP 1 LAST LOCATION R25W4
J 0
(-7875 4150);
DISPLAY 0.617021 (-7875 4150);
PAINT GREEN (-7875 4150);
FORCEPROP 1 LAST VALUE 120R2F-GP
J 0
(-7325 4150);
DISPLAY 0.617021 (-7325 4150);
PAINT GREEN (-7325 4150);
FORCEPROP 1 LAST PATH I162
R 1
J 0
(-7525 4150);
DISPLAY 0.617021 (-7525 4150);
PAINT GREEN (-7525 4150);
DISPLAY INVISIBLE (-7525 4150);
FORCEPROP 1 LAST PACK_TYPE RCL_GP
R 1
J 0
(-7525 4150);
DISPLAY 0.617021 (-7525 4150);
PAINT GREEN (-7525 4150);
DISPLAY INVISIBLE (-7525 4150);
FORCEPROP 1 LAST PART_NUMBER 64.12005.6DL
R 1
J 0
(-7525 4150);
DISPLAY 0.617021 (-7525 4150);
PAINT GREEN (-7525 4150);
DISPLAY INVISIBLE (-7525 4150);
FORCEPROP 1 LAST CDS_LMAN_SYM_OUTLINE -50,75,50,-75
R 1
J 0
(-7525 4150);
DISPLAY 0.468085 (-7525 4150);
PAINT GREEN (-7525 4150);
DISPLAY INVISIBLE (-7525 4150);
FORCEPROP 2 LAST CDS_LIB w_hdl
J 0
(-7525 4150);
PAINT MONO (-7525 4150);
DISPLAY INVISIBLE (-7525 4150);
FORCEADD 120R2F-GP..1
R 1
(-7525 4200);
FORCEPROP 1 LAST LOCATION R25W3
J 0
(-7875 4200);
DISPLAY 0.617021 (-7875 4200);
PAINT GREEN (-7875 4200);
FORCEPROP 1 LAST VALUE 120R2F-GP
J 0
(-7325 4200);
DISPLAY 0.617021 (-7325 4200);
PAINT GREEN (-7325 4200);
FORCEPROP 1 LAST PATH I163
R 1
J 0
(-7525 4200);
DISPLAY 0.617021 (-7525 4200);
PAINT GREEN (-7525 4200);
DISPLAY INVISIBLE (-7525 4200);
FORCEPROP 1 LAST PACK_TYPE RCL_GP
R 1
J 0
(-7525 4200);
DISPLAY 0.617021 (-7525 4200);
PAINT GREEN (-7525 4200);
DISPLAY INVISIBLE (-7525 4200);
FORCEPROP 1 LAST PART_NUMBER 64.12005.6DL
R 1
J 0
(-7525 4200);
DISPLAY 0.617021 (-7525 4200);
PAINT GREEN (-7525 4200);
DISPLAY INVISIBLE (-7525 4200);
FORCEPROP 2 LAST CDS_LIB w_hdl
R 1
J 0
(-7525 4200);
PAINT MONO (-7525 4200);
DISPLAY INVISIBLE (-7525 4200);
FORCEPROP 1 LAST CDS_LMAN_SYM_OUTLINE -50,75,50,-75
R 1
J 0
(-7525 4200);
DISPLAY 0.468085 (-7525 4200);
PAINT GREEN (-7525 4200);
DISPLAY INVISIBLE (-7525 4200);
FORCEADD 120R2F-GP..1
R 1
(-7525 4100);
FORCEPROP 1 LAST LOCATION R25W5
J 0
(-7875 4100);
DISPLAY 0.617021 (-7875 4100);
PAINT GREEN (-7875 4100);
FORCEPROP 1 LAST VALUE 120R2F-GP
J 0
(-7325 4100);
DISPLAY 0.617021 (-7325 4100);
PAINT GREEN (-7325 4100);
FORCEPROP 1 LAST PATH I164
R 1
J 0
(-7525 4100);
DISPLAY 0.617021 (-7525 4100);
PAINT GREEN (-7525 4100);
DISPLAY INVISIBLE (-7525 4100);
FORCEPROP 1 LAST PACK_TYPE RCL_GP
R 1
J 0
(-7525 4100);
DISPLAY 0.617021 (-7525 4100);
PAINT GREEN (-7525 4100);
DISPLAY INVISIBLE (-7525 4100);
FORCEPROP 1 LAST PART_NUMBER 64.12005.6DL
R 1
J 0
(-7525 4100);
DISPLAY 0.617021 (-7525 4100);
PAINT GREEN (-7525 4100);
DISPLAY INVISIBLE (-7525 4100);
FORCEPROP 2 LAST CDS_LIB w_hdl
R 1
J 0
(-7525 4100);
PAINT MONO (-7525 4100);
DISPLAY INVISIBLE (-7525 4100);
FORCEPROP 1 LAST CDS_LMAN_SYM_OUTLINE -50,75,50,-75
R 1
J 0
(-7525 4100);
DISPLAY 0.468085 (-7525 4100);
PAINT GREEN (-7525 4100);
DISPLAY INVISIBLE (-7525 4100);
FORCEADD 120R2F-GP..1
R 1
(-7525 4050);
FORCEPROP 1 LAST LOCATION R25W6
J 0
(-7875 4050);
DISPLAY 0.617021 (-7875 4050);
PAINT GREEN (-7875 4050);
FORCEPROP 1 LAST VALUE 120R2F-GP
J 0
(-7325 4050);
DISPLAY 0.617021 (-7325 4050);
PAINT GREEN (-7325 4050);
FORCEPROP 1 LAST PATH I165
R 1
J 0
(-7525 4050);
DISPLAY 0.617021 (-7525 4050);
PAINT GREEN (-7525 4050);
DISPLAY INVISIBLE (-7525 4050);
FORCEPROP 1 LAST PACK_TYPE RCL_GP
R 1
J 0
(-7525 4050);
DISPLAY 0.617021 (-7525 4050);
PAINT GREEN (-7525 4050);
DISPLAY INVISIBLE (-7525 4050);
FORCEPROP 1 LAST PART_NUMBER 64.12005.6DL
R 1
J 0
(-7525 4050);
DISPLAY 0.617021 (-7525 4050);
PAINT GREEN (-7525 4050);
DISPLAY INVISIBLE (-7525 4050);
FORCEPROP 1 LAST CDS_LMAN_SYM_OUTLINE -50,75,50,-75
R 1
J 0
(-7525 4050);
DISPLAY 0.468085 (-7525 4050);
PAINT GREEN (-7525 4050);
DISPLAY INVISIBLE (-7525 4050);
FORCEPROP 2 LAST CDS_LIB w_hdl
J 0
(-7525 4050);
PAINT MONO (-7525 4050);
DISPLAY INVISIBLE (-7525 4050);
FORCEADD 120R2F-GP..1
R 1
(-7525 4000);
FORCEPROP 1 LAST LOCATION R25W7
J 0
(-7875 4000);
DISPLAY 0.617021 (-7875 4000);
PAINT GREEN (-7875 4000);
FORCEPROP 1 LAST VALUE 120R2F-GP
J 0
(-7325 4000);
DISPLAY 0.617021 (-7325 4000);
PAINT GREEN (-7325 4000);
FORCEPROP 1 LAST PATH I166
R 1
J 0
(-7525 4000);
DISPLAY 0.617021 (-7525 4000);
PAINT GREEN (-7525 4000);
DISPLAY INVISIBLE (-7525 4000);
FORCEPROP 1 LAST PACK_TYPE RCL_GP
R 1
J 0
(-7525 4000);
DISPLAY 0.617021 (-7525 4000);
PAINT GREEN (-7525 4000);
DISPLAY INVISIBLE (-7525 4000);
FORCEPROP 1 LAST PART_NUMBER 64.12005.6DL
R 1
J 0
(-7525 4000);
DISPLAY 0.617021 (-7525 4000);
PAINT GREEN (-7525 4000);
DISPLAY INVISIBLE (-7525 4000);
FORCEPROP 2 LAST CDS_LIB w_hdl
R 1
J 0
(-7525 4000);
PAINT MONO (-7525 4000);
DISPLAY INVISIBLE (-7525 4000);
FORCEPROP 1 LAST CDS_LMAN_SYM_OUTLINE -50,75,50,-75
R 1
J 0
(-7525 4000);
DISPLAY 0.468085 (-7525 4000);
PAINT GREEN (-7525 4000);
DISPLAY INVISIBLE (-7525 4000);
FORCEADD 120R2F-GP..1
R 1
(-7525 3950);
FORCEPROP 1 LAST LOCATION R25W8
J 0
(-7875 3950);
DISPLAY 0.617021 (-7875 3950);
PAINT GREEN (-7875 3950);
FORCEPROP 1 LAST VALUE 120R2F-GP
J 0
(-7325 3950);
DISPLAY 0.617021 (-7325 3950);
PAINT GREEN (-7325 3950);
FORCEPROP 1 LAST PATH I167
R 1
J 0
(-7525 3950);
DISPLAY 0.617021 (-7525 3950);
PAINT GREEN (-7525 3950);
DISPLAY INVISIBLE (-7525 3950);
FORCEPROP 1 LAST PACK_TYPE RCL_GP
R 1
J 0
(-7525 3950);
DISPLAY 0.617021 (-7525 3950);
PAINT GREEN (-7525 3950);
DISPLAY INVISIBLE (-7525 3950);
FORCEPROP 1 LAST PART_NUMBER 64.12005.6DL
R 1
J 0
(-7525 3950);
DISPLAY 0.617021 (-7525 3950);
PAINT GREEN (-7525 3950);
DISPLAY INVISIBLE (-7525 3950);
FORCEPROP 1 LAST CDS_LMAN_SYM_OUTLINE -50,75,50,-75
R 1
J 0
(-7525 3950);
DISPLAY 0.468085 (-7525 3950);
PAINT GREEN (-7525 3950);
DISPLAY INVISIBLE (-7525 3950);
FORCEPROP 2 LAST CDS_LIB w_hdl
J 0
(-7525 3950);
PAINT MONO (-7525 3950);
DISPLAY INVISIBLE (-7525 3950);
FORCEADD 120R2F-GP..1
R 1
(-7525 3900);
FORCEPROP 1 LAST LOCATION R25W9
J 0
(-7875 3900);
DISPLAY 0.617021 (-7875 3900);
PAINT GREEN (-7875 3900);
FORCEPROP 1 LAST VALUE 120R2F-GP
J 0
(-7325 3900);
DISPLAY 0.617021 (-7325 3900);
PAINT GREEN (-7325 3900);
FORCEPROP 1 LAST PATH I168
R 1
J 0
(-7525 3900);
DISPLAY 0.617021 (-7525 3900);
PAINT GREEN (-7525 3900);
DISPLAY INVISIBLE (-7525 3900);
FORCEPROP 1 LAST PACK_TYPE RCL_GP
R 1
J 0
(-7525 3900);
DISPLAY 0.617021 (-7525 3900);
PAINT GREEN (-7525 3900);
DISPLAY INVISIBLE (-7525 3900);
FORCEPROP 1 LAST PART_NUMBER 64.12005.6DL
R 1
J 0
(-7525 3900);
DISPLAY 0.617021 (-7525 3900);
PAINT GREEN (-7525 3900);
DISPLAY INVISIBLE (-7525 3900);
FORCEPROP 2 LAST CDS_LIB w_hdl
R 1
J 0
(-7525 3900);
PAINT MONO (-7525 3900);
DISPLAY INVISIBLE (-7525 3900);
FORCEPROP 1 LAST CDS_LMAN_SYM_OUTLINE -50,75,50,-75
R 1
J 0
(-7525 3900);
DISPLAY 0.468085 (-7525 3900);
PAINT GREEN (-7525 3900);
DISPLAY INVISIBLE (-7525 3900);
FORCEADD 120R2F-GP..1
R 1
(-7525 3850);
FORCEPROP 1 LAST LOCATION R25W10
J 0
(-7875 3850);
DISPLAY 0.617021 (-7875 3850);
PAINT GREEN (-7875 3850);
FORCEPROP 1 LAST VALUE 120R2F-GP
J 0
(-7325 3850);
DISPLAY 0.617021 (-7325 3850);
PAINT GREEN (-7325 3850);
FORCEPROP 1 LAST PATH I169
R 1
J 0
(-7525 3850);
DISPLAY 0.617021 (-7525 3850);
PAINT GREEN (-7525 3850);
DISPLAY INVISIBLE (-7525 3850);
FORCEPROP 1 LAST PACK_TYPE RCL_GP
R 1
J 0
(-7525 3850);
DISPLAY 0.617021 (-7525 3850);
PAINT GREEN (-7525 3850);
DISPLAY INVISIBLE (-7525 3850);
FORCEPROP 1 LAST PART_NUMBER 64.12005.6DL
R 1
J 0
(-7525 3850);
DISPLAY 0.617021 (-7525 3850);
PAINT GREEN (-7525 3850);
DISPLAY INVISIBLE (-7525 3850);
FORCEPROP 1 LAST CDS_LMAN_SYM_OUTLINE -50,75,50,-75
R 1
J 0
(-7525 3850);
DISPLAY 0.468085 (-7525 3850);
PAINT GREEN (-7525 3850);
DISPLAY INVISIBLE (-7525 3850);
FORCEPROP 2 LAST CDS_LIB w_hdl
J 0
(-7525 3850);
PAINT MONO (-7525 3850);
DISPLAY INVISIBLE (-7525 3850);
FORCEADD OFFPAGE..3
(-875 3500);
FORCEPROP 2 LAST $XR0 143 
J 0
(-661 3500);
DISPLAY 0.638298 (-661 3500);
PAINT MONO (-661 3500);
FORCEPROP 2 LAST $XR1 149 
J 0
(-541 3500);
DISPLAY 0.638298 (-541 3500);
PAINT MONO (-541 3500);
FORCEPROP 1 LAST COMMENT_BODY TRUE
J 0
(-925 3400);
DISPLAY 0.872340 (-925 3400);
PAINT GREEN (-925 3400);
DISPLAY INVISIBLE (-925 3400);
FORCEPROP 1 LAST OFFPAGE TRUE
J 0
(-550 3375);
DISPLAY 0.872340 (-550 3375);
PAINT GREEN (-550 3375);
DISPLAY INVISIBLE (-550 3375);
FORCEPROP 2 LAST CDS_LIB mstr_standard
J 0
(-875 3500);
PAINT MONO (-875 3500);
DISPLAY INVISIBLE (-875 3500);
FORCEPROP 2 LAST PATH I17
J 0
(-525 3550);
DISPLAY 1.021277 (-525 3550);
PAINT ORANGE (-525 3550);
DISPLAY INVISIBLE (-525 3550);
FORCEADD 120R2F-GP..1
R 1
(-7525 3750);
FORCEPROP 1 LAST LOCATION R25W12
J 0
(-7875 3750);
DISPLAY 0.617021 (-7875 3750);
PAINT GREEN (-7875 3750);
FORCEPROP 1 LAST VALUE 120R2F-GP
J 0
(-7325 3750);
DISPLAY 0.617021 (-7325 3750);
PAINT GREEN (-7325 3750);
FORCEPROP 1 LAST PATH I170
R 1
J 0
(-7525 3750);
DISPLAY 0.617021 (-7525 3750);
PAINT GREEN (-7525 3750);
DISPLAY INVISIBLE (-7525 3750);
FORCEPROP 1 LAST PACK_TYPE RCL_GP
R 1
J 0
(-7525 3750);
DISPLAY 0.617021 (-7525 3750);
PAINT GREEN (-7525 3750);
DISPLAY INVISIBLE (-7525 3750);
FORCEPROP 1 LAST PART_NUMBER 64.12005.6DL
R 1
J 0
(-7525 3750);
DISPLAY 0.617021 (-7525 3750);
PAINT GREEN (-7525 3750);
DISPLAY INVISIBLE (-7525 3750);
FORCEPROP 1 LAST CDS_LMAN_SYM_OUTLINE -50,75,50,-75
R 1
J 0
(-7525 3750);
DISPLAY 0.468085 (-7525 3750);
PAINT GREEN (-7525 3750);
DISPLAY INVISIBLE (-7525 3750);
FORCEPROP 2 LAST CDS_LIB w_hdl
J 0
(-7525 3750);
PAINT MONO (-7525 3750);
DISPLAY INVISIBLE (-7525 3750);
FORCEADD 120R2F-GP..1
R 1
(-7525 3800);
FORCEPROP 1 LAST LOCATION R25W11
J 0
(-7875 3800);
DISPLAY 0.617021 (-7875 3800);
PAINT GREEN (-7875 3800);
FORCEPROP 1 LAST VALUE 120R2F-GP
J 0
(-7325 3800);
DISPLAY 0.617021 (-7325 3800);
PAINT GREEN (-7325 3800);
FORCEPROP 1 LAST PATH I171
R 1
J 0
(-7525 3800);
DISPLAY 0.617021 (-7525 3800);
PAINT GREEN (-7525 3800);
DISPLAY INVISIBLE (-7525 3800);
FORCEPROP 1 LAST PACK_TYPE RCL_GP
R 1
J 0
(-7525 3800);
DISPLAY 0.617021 (-7525 3800);
PAINT GREEN (-7525 3800);
DISPLAY INVISIBLE (-7525 3800);
FORCEPROP 1 LAST PART_NUMBER 64.12005.6DL
R 1
J 0
(-7525 3800);
DISPLAY 0.617021 (-7525 3800);
PAINT GREEN (-7525 3800);
DISPLAY INVISIBLE (-7525 3800);
FORCEPROP 2 LAST CDS_LIB w_hdl
R 1
J 0
(-7525 3800);
PAINT MONO (-7525 3800);
DISPLAY INVISIBLE (-7525 3800);
FORCEPROP 1 LAST CDS_LMAN_SYM_OUTLINE -50,75,50,-75
R 1
J 0
(-7525 3800);
DISPLAY 0.468085 (-7525 3800);
PAINT GREEN (-7525 3800);
DISPLAY INVISIBLE (-7525 3800);
FORCEADD 120R2F-GP..1
R 1
(-7525 3700);
FORCEPROP 1 LAST LOCATION R25W13
J 0
(-7875 3700);
DISPLAY 0.617021 (-7875 3700);
PAINT GREEN (-7875 3700);
FORCEPROP 1 LAST VALUE 120R2F-GP
J 0
(-7325 3700);
DISPLAY 0.617021 (-7325 3700);
PAINT GREEN (-7325 3700);
FORCEPROP 1 LAST PATH I172
R 1
J 0
(-7525 3700);
DISPLAY 0.617021 (-7525 3700);
PAINT GREEN (-7525 3700);
DISPLAY INVISIBLE (-7525 3700);
FORCEPROP 1 LAST PACK_TYPE RCL_GP
R 1
J 0
(-7525 3700);
DISPLAY 0.617021 (-7525 3700);
PAINT GREEN (-7525 3700);
DISPLAY INVISIBLE (-7525 3700);
FORCEPROP 1 LAST PART_NUMBER 64.12005.6DL
R 1
J 0
(-7525 3700);
DISPLAY 0.617021 (-7525 3700);
PAINT GREEN (-7525 3700);
DISPLAY INVISIBLE (-7525 3700);
FORCEPROP 2 LAST CDS_LIB w_hdl
R 1
J 0
(-7525 3700);
PAINT MONO (-7525 3700);
DISPLAY INVISIBLE (-7525 3700);
FORCEPROP 1 LAST CDS_LMAN_SYM_OUTLINE -50,75,50,-75
R 1
J 0
(-7525 3700);
DISPLAY 0.468085 (-7525 3700);
PAINT GREEN (-7525 3700);
DISPLAY INVISIBLE (-7525 3700);
FORCEADD 120R2F-GP..1
R 1
(-7525 3550);
FORCEPROP 1 LAST LOCATION R25W16
J 0
(-7875 3550);
DISPLAY 0.617021 (-7875 3550);
PAINT GREEN (-7875 3550);
FORCEPROP 1 LAST VALUE 120R2F-GP
J 0
(-7325 3550);
DISPLAY 0.617021 (-7325 3550);
PAINT GREEN (-7325 3550);
FORCEPROP 1 LAST PATH I173
R 1
J 0
(-7525 3550);
DISPLAY 0.617021 (-7525 3550);
PAINT GREEN (-7525 3550);
DISPLAY INVISIBLE (-7525 3550);
FORCEPROP 1 LAST PACK_TYPE RCL_GP
R 1
J 0
(-7525 3550);
DISPLAY 0.617021 (-7525 3550);
PAINT GREEN (-7525 3550);
DISPLAY INVISIBLE (-7525 3550);
FORCEPROP 1 LAST PART_NUMBER 64.12005.6DL
R 1
J 0
(-7525 3550);
DISPLAY 0.617021 (-7525 3550);
PAINT GREEN (-7525 3550);
DISPLAY INVISIBLE (-7525 3550);
FORCEPROP 1 LAST CDS_LMAN_SYM_OUTLINE -50,75,50,-75
R 1
J 0
(-7525 3550);
DISPLAY 0.468085 (-7525 3550);
PAINT GREEN (-7525 3550);
DISPLAY INVISIBLE (-7525 3550);
FORCEPROP 2 LAST CDS_LIB w_hdl
J 0
(-7525 3550);
PAINT MONO (-7525 3550);
DISPLAY INVISIBLE (-7525 3550);
FORCEADD 120R2F-GP..1
R 1
(-7525 3600);
FORCEPROP 1 LAST LOCATION R25W15
J 0
(-7875 3600);
DISPLAY 0.617021 (-7875 3600);
PAINT GREEN (-7875 3600);
FORCEPROP 1 LAST VALUE 120R2F-GP
J 0
(-7325 3600);
DISPLAY 0.617021 (-7325 3600);
PAINT GREEN (-7325 3600);
FORCEPROP 1 LAST PATH I174
R 1
J 0
(-7525 3600);
DISPLAY 0.617021 (-7525 3600);
PAINT GREEN (-7525 3600);
DISPLAY INVISIBLE (-7525 3600);
FORCEPROP 1 LAST PACK_TYPE RCL_GP
R 1
J 0
(-7525 3600);
DISPLAY 0.617021 (-7525 3600);
PAINT GREEN (-7525 3600);
DISPLAY INVISIBLE (-7525 3600);
FORCEPROP 1 LAST PART_NUMBER 64.12005.6DL
R 1
J 0
(-7525 3600);
DISPLAY 0.617021 (-7525 3600);
PAINT GREEN (-7525 3600);
DISPLAY INVISIBLE (-7525 3600);
FORCEPROP 2 LAST CDS_LIB w_hdl
R 1
J 0
(-7525 3600);
PAINT MONO (-7525 3600);
DISPLAY INVISIBLE (-7525 3600);
FORCEPROP 1 LAST CDS_LMAN_SYM_OUTLINE -50,75,50,-75
R 1
J 0
(-7525 3600);
DISPLAY 0.468085 (-7525 3600);
PAINT GREEN (-7525 3600);
DISPLAY INVISIBLE (-7525 3600);
FORCEADD 120R2F-GP..1
R 1
(-7525 3650);
FORCEPROP 1 LAST LOCATION R25W14
J 0
(-7875 3650);
DISPLAY 0.617021 (-7875 3650);
PAINT GREEN (-7875 3650);
FORCEPROP 1 LAST VALUE 120R2F-GP
J 0
(-7325 3650);
DISPLAY 0.617021 (-7325 3650);
PAINT GREEN (-7325 3650);
FORCEPROP 1 LAST PATH I175
R 1
J 0
(-7525 3650);
DISPLAY 0.617021 (-7525 3650);
PAINT GREEN (-7525 3650);
DISPLAY INVISIBLE (-7525 3650);
FORCEPROP 1 LAST PACK_TYPE RCL_GP
R 1
J 0
(-7525 3650);
DISPLAY 0.617021 (-7525 3650);
PAINT GREEN (-7525 3650);
DISPLAY INVISIBLE (-7525 3650);
FORCEPROP 1 LAST PART_NUMBER 64.12005.6DL
R 1
J 0
(-7525 3650);
DISPLAY 0.617021 (-7525 3650);
PAINT GREEN (-7525 3650);
DISPLAY INVISIBLE (-7525 3650);
FORCEPROP 1 LAST CDS_LMAN_SYM_OUTLINE -50,75,50,-75
R 1
J 0
(-7525 3650);
DISPLAY 0.468085 (-7525 3650);
PAINT GREEN (-7525 3650);
DISPLAY INVISIBLE (-7525 3650);
FORCEPROP 2 LAST CDS_LIB w_hdl
J 0
(-7525 3650);
PAINT MONO (-7525 3650);
DISPLAY INVISIBLE (-7525 3650);
FORCEADD 120R2F-GP..1
R 1
(-7525 3250);
FORCEPROP 1 LAST LOCATION R25W22
J 0
(-7875 3250);
DISPLAY 0.617021 (-7875 3250);
PAINT GREEN (-7875 3250);
FORCEPROP 1 LAST VALUE 120R2F-GP
J 0
(-7325 3250);
DISPLAY 0.617021 (-7325 3250);
PAINT GREEN (-7325 3250);
FORCEPROP 1 LAST PATH I176
R 1
J 0
(-7525 3250);
DISPLAY 0.617021 (-7525 3250);
PAINT GREEN (-7525 3250);
DISPLAY INVISIBLE (-7525 3250);
FORCEPROP 1 LAST PACK_TYPE RCL_GP
R 1
J 0
(-7525 3250);
DISPLAY 0.617021 (-7525 3250);
PAINT GREEN (-7525 3250);
DISPLAY INVISIBLE (-7525 3250);
FORCEPROP 1 LAST PART_NUMBER 64.12005.6DL
R 1
J 0
(-7525 3250);
DISPLAY 0.617021 (-7525 3250);
PAINT GREEN (-7525 3250);
DISPLAY INVISIBLE (-7525 3250);
FORCEPROP 1 LAST CDS_LMAN_SYM_OUTLINE -50,75,50,-75
R 1
J 0
(-7525 3250);
DISPLAY 0.468085 (-7525 3250);
PAINT GREEN (-7525 3250);
DISPLAY INVISIBLE (-7525 3250);
FORCEPROP 2 LAST CDS_LIB w_hdl
J 0
(-7525 3250);
PAINT MONO (-7525 3250);
DISPLAY INVISIBLE (-7525 3250);
FORCEADD 120R2F-GP..1
R 1
(-7525 3200);
FORCEPROP 1 LAST LOCATION R25W23
J 0
(-7875 3200);
DISPLAY 0.617021 (-7875 3200);
PAINT GREEN (-7875 3200);
FORCEPROP 1 LAST VALUE 120R2F-GP
J 0
(-7325 3200);
DISPLAY 0.617021 (-7325 3200);
PAINT GREEN (-7325 3200);
FORCEPROP 1 LAST PATH I177
R 1
J 0
(-7525 3200);
DISPLAY 0.617021 (-7525 3200);
PAINT GREEN (-7525 3200);
DISPLAY INVISIBLE (-7525 3200);
FORCEPROP 1 LAST PACK_TYPE RCL_GP
R 1
J 0
(-7525 3200);
DISPLAY 0.617021 (-7525 3200);
PAINT GREEN (-7525 3200);
DISPLAY INVISIBLE (-7525 3200);
FORCEPROP 1 LAST PART_NUMBER 64.12005.6DL
R 1
J 0
(-7525 3200);
DISPLAY 0.617021 (-7525 3200);
PAINT GREEN (-7525 3200);
DISPLAY INVISIBLE (-7525 3200);
FORCEPROP 2 LAST CDS_LIB w_hdl
R 1
J 0
(-7525 3200);
PAINT MONO (-7525 3200);
DISPLAY INVISIBLE (-7525 3200);
FORCEPROP 1 LAST CDS_LMAN_SYM_OUTLINE -50,75,50,-75
R 1
J 0
(-7525 3200);
DISPLAY 0.468085 (-7525 3200);
PAINT GREEN (-7525 3200);
DISPLAY INVISIBLE (-7525 3200);
FORCEADD 120R2F-GP..1
R 1
(-7525 3150);
FORCEPROP 1 LAST LOCATION R25W24
J 0
(-7875 3150);
DISPLAY 0.617021 (-7875 3150);
PAINT GREEN (-7875 3150);
FORCEPROP 1 LAST VALUE 120R2F-GP
J 0
(-7325 3150);
DISPLAY 0.617021 (-7325 3150);
PAINT GREEN (-7325 3150);
FORCEPROP 1 LAST PATH I178
R 1
J 0
(-7525 3150);
DISPLAY 0.617021 (-7525 3150);
PAINT GREEN (-7525 3150);
DISPLAY INVISIBLE (-7525 3150);
FORCEPROP 1 LAST PACK_TYPE RCL_GP
R 1
J 0
(-7525 3150);
DISPLAY 0.617021 (-7525 3150);
PAINT GREEN (-7525 3150);
DISPLAY INVISIBLE (-7525 3150);
FORCEPROP 1 LAST PART_NUMBER 64.12005.6DL
R 1
J 0
(-7525 3150);
DISPLAY 0.617021 (-7525 3150);
PAINT GREEN (-7525 3150);
DISPLAY INVISIBLE (-7525 3150);
FORCEPROP 1 LAST CDS_LMAN_SYM_OUTLINE -50,75,50,-75
R 1
J 0
(-7525 3150);
DISPLAY 0.468085 (-7525 3150);
PAINT GREEN (-7525 3150);
DISPLAY INVISIBLE (-7525 3150);
FORCEPROP 2 LAST CDS_LIB w_hdl
J 0
(-7525 3150);
PAINT MONO (-7525 3150);
DISPLAY INVISIBLE (-7525 3150);
FORCEADD 120R2F-GP..1
R 1
(-7525 3100);
FORCEPROP 1 LAST LOCATION R25W25
J 0
(-7875 3100);
DISPLAY 0.617021 (-7875 3100);
PAINT GREEN (-7875 3100);
FORCEPROP 1 LAST VALUE 120R2F-GP
J 0
(-7325 3100);
DISPLAY 0.617021 (-7325 3100);
PAINT GREEN (-7325 3100);
FORCEPROP 1 LAST PATH I179
R 1
J 0
(-7525 3100);
DISPLAY 0.617021 (-7525 3100);
PAINT GREEN (-7525 3100);
DISPLAY INVISIBLE (-7525 3100);
FORCEPROP 1 LAST PACK_TYPE RCL_GP
R 1
J 0
(-7525 3100);
DISPLAY 0.617021 (-7525 3100);
PAINT GREEN (-7525 3100);
DISPLAY INVISIBLE (-7525 3100);
FORCEPROP 1 LAST PART_NUMBER 64.12005.6DL
R 1
J 0
(-7525 3100);
DISPLAY 0.617021 (-7525 3100);
PAINT GREEN (-7525 3100);
DISPLAY INVISIBLE (-7525 3100);
FORCEPROP 2 LAST CDS_LIB w_hdl
R 1
J 0
(-7525 3100);
PAINT MONO (-7525 3100);
DISPLAY INVISIBLE (-7525 3100);
FORCEPROP 1 LAST CDS_LMAN_SYM_OUTLINE -50,75,50,-75
R 1
J 0
(-7525 3100);
DISPLAY 0.468085 (-7525 3100);
PAINT GREEN (-7525 3100);
DISPLAY INVISIBLE (-7525 3100);
FORCEADD OFFPAGE..3
(-875 3350);
FORCEPROP 2 LAST $XR0 143 
J 0
(-661 3350);
DISPLAY 0.638298 (-661 3350);
PAINT MONO (-661 3350);
FORCEPROP 2 LAST $XR1 149 
J 0
(-541 3350);
DISPLAY 0.638298 (-541 3350);
PAINT MONO (-541 3350);
FORCEPROP 1 LAST COMMENT_BODY TRUE
J 0
(-925 3250);
DISPLAY 0.872340 (-925 3250);
PAINT GREEN (-925 3250);
DISPLAY INVISIBLE (-925 3250);
FORCEPROP 1 LAST OFFPAGE TRUE
J 0
(-550 3225);
DISPLAY 0.872340 (-550 3225);
PAINT GREEN (-550 3225);
DISPLAY INVISIBLE (-550 3225);
FORCEPROP 2 LAST CDS_LIB mstr_standard
J 0
(-875 3350);
PAINT MONO (-875 3350);
DISPLAY INVISIBLE (-875 3350);
FORCEPROP 2 LAST PATH I18
J 0
(-525 3400);
DISPLAY 1.021277 (-525 3400);
PAINT ORANGE (-525 3400);
DISPLAY INVISIBLE (-525 3400);
FORCEADD 120R2F-GP..1
R 1
(-7525 3050);
FORCEPROP 1 LAST LOCATION R25W26
J 0
(-7875 3050);
DISPLAY 0.617021 (-7875 3050);
PAINT GREEN (-7875 3050);
FORCEPROP 1 LAST VALUE 120R2F-GP
J 0
(-7325 3050);
DISPLAY 0.617021 (-7325 3050);
PAINT GREEN (-7325 3050);
FORCEPROP 1 LAST PATH I180
R 1
J 0
(-7525 3050);
DISPLAY 0.617021 (-7525 3050);
PAINT GREEN (-7525 3050);
DISPLAY INVISIBLE (-7525 3050);
FORCEPROP 2 LAST CDS_LIB w_hdl
J 0
(-7525 3050);
PAINT MONO (-7525 3050);
DISPLAY INVISIBLE (-7525 3050);
FORCEPROP 1 LAST CDS_LMAN_SYM_OUTLINE -50,75,50,-75
R 1
J 0
(-7525 3050);
DISPLAY 0.468085 (-7525 3050);
PAINT GREEN (-7525 3050);
DISPLAY INVISIBLE (-7525 3050);
FORCEPROP 1 LAST PART_NUMBER 64.12005.6DL
R 1
J 0
(-7525 3050);
DISPLAY 0.617021 (-7525 3050);
PAINT GREEN (-7525 3050);
DISPLAY INVISIBLE (-7525 3050);
FORCEPROP 1 LAST PACK_TYPE RCL_GP
R 1
J 0
(-7525 3050);
DISPLAY 0.617021 (-7525 3050);
PAINT GREEN (-7525 3050);
DISPLAY INVISIBLE (-7525 3050);
FORCEADD 120R2F-GP..1
R 1
(-7525 3500);
FORCEPROP 1 LAST LOCATION R25W17
J 0
(-7875 3500);
DISPLAY 0.617021 (-7875 3500);
PAINT GREEN (-7875 3500);
FORCEPROP 1 LAST VALUE 120R2F-GP
J 0
(-7325 3500);
DISPLAY 0.617021 (-7325 3500);
PAINT GREEN (-7325 3500);
FORCEPROP 1 LAST PATH I181
R 1
J 0
(-7525 3500);
DISPLAY 0.617021 (-7525 3500);
PAINT GREEN (-7525 3500);
DISPLAY INVISIBLE (-7525 3500);
FORCEPROP 1 LAST PACK_TYPE RCL_GP
R 1
J 0
(-7525 3500);
DISPLAY 0.617021 (-7525 3500);
PAINT GREEN (-7525 3500);
DISPLAY INVISIBLE (-7525 3500);
FORCEPROP 1 LAST PART_NUMBER 64.12005.6DL
R 1
J 0
(-7525 3500);
DISPLAY 0.617021 (-7525 3500);
PAINT GREEN (-7525 3500);
DISPLAY INVISIBLE (-7525 3500);
FORCEPROP 2 LAST CDS_LIB w_hdl
R 1
J 0
(-7525 3500);
PAINT MONO (-7525 3500);
DISPLAY INVISIBLE (-7525 3500);
FORCEPROP 1 LAST CDS_LMAN_SYM_OUTLINE -50,75,50,-75
R 1
J 0
(-7525 3500);
DISPLAY 0.468085 (-7525 3500);
PAINT GREEN (-7525 3500);
DISPLAY INVISIBLE (-7525 3500);
FORCEADD 120R2F-GP..1
R 1
(-7525 3450);
FORCEPROP 1 LAST LOCATION R25W18
J 0
(-7875 3450);
DISPLAY 0.617021 (-7875 3450);
PAINT GREEN (-7875 3450);
FORCEPROP 1 LAST VALUE 120R2F-GP
J 0
(-7325 3450);
DISPLAY 0.617021 (-7325 3450);
PAINT GREEN (-7325 3450);
FORCEPROP 1 LAST PATH I182
R 1
J 0
(-7525 3450);
DISPLAY 0.617021 (-7525 3450);
PAINT GREEN (-7525 3450);
DISPLAY INVISIBLE (-7525 3450);
FORCEPROP 1 LAST PACK_TYPE RCL_GP
R 1
J 0
(-7525 3450);
DISPLAY 0.617021 (-7525 3450);
PAINT GREEN (-7525 3450);
DISPLAY INVISIBLE (-7525 3450);
FORCEPROP 1 LAST PART_NUMBER 64.12005.6DL
R 1
J 0
(-7525 3450);
DISPLAY 0.617021 (-7525 3450);
PAINT GREEN (-7525 3450);
DISPLAY INVISIBLE (-7525 3450);
FORCEPROP 1 LAST CDS_LMAN_SYM_OUTLINE -50,75,50,-75
R 1
J 0
(-7525 3450);
DISPLAY 0.468085 (-7525 3450);
PAINT GREEN (-7525 3450);
DISPLAY INVISIBLE (-7525 3450);
FORCEPROP 2 LAST CDS_LIB w_hdl
J 0
(-7525 3450);
PAINT MONO (-7525 3450);
DISPLAY INVISIBLE (-7525 3450);
FORCEADD 120R2F-GP..1
R 1
(-7525 3400);
FORCEPROP 1 LAST LOCATION R25W19
J 0
(-7875 3400);
DISPLAY 0.617021 (-7875 3400);
PAINT GREEN (-7875 3400);
FORCEPROP 1 LAST VALUE 120R2F-GP
J 0
(-7325 3400);
DISPLAY 0.617021 (-7325 3400);
PAINT GREEN (-7325 3400);
FORCEPROP 1 LAST PATH I183
R 1
J 0
(-7525 3400);
DISPLAY 0.617021 (-7525 3400);
PAINT GREEN (-7525 3400);
DISPLAY INVISIBLE (-7525 3400);
FORCEPROP 1 LAST PACK_TYPE RCL_GP
R 1
J 0
(-7525 3400);
DISPLAY 0.617021 (-7525 3400);
PAINT GREEN (-7525 3400);
DISPLAY INVISIBLE (-7525 3400);
FORCEPROP 1 LAST PART_NUMBER 64.12005.6DL
R 1
J 0
(-7525 3400);
DISPLAY 0.617021 (-7525 3400);
PAINT GREEN (-7525 3400);
DISPLAY INVISIBLE (-7525 3400);
FORCEPROP 2 LAST CDS_LIB w_hdl
R 1
J 0
(-7525 3400);
PAINT MONO (-7525 3400);
DISPLAY INVISIBLE (-7525 3400);
FORCEPROP 1 LAST CDS_LMAN_SYM_OUTLINE -50,75,50,-75
R 1
J 0
(-7525 3400);
DISPLAY 0.468085 (-7525 3400);
PAINT GREEN (-7525 3400);
DISPLAY INVISIBLE (-7525 3400);
FORCEADD 120R2F-GP..1
R 1
(-7525 3350);
FORCEPROP 1 LAST LOCATION R25W20
J 0
(-7875 3350);
DISPLAY 0.617021 (-7875 3350);
PAINT GREEN (-7875 3350);
FORCEPROP 1 LAST VALUE 120R2F-GP
J 0
(-7325 3350);
DISPLAY 0.617021 (-7325 3350);
PAINT GREEN (-7325 3350);
FORCEPROP 1 LAST PATH I184
R 1
J 0
(-7525 3350);
DISPLAY 0.617021 (-7525 3350);
PAINT GREEN (-7525 3350);
DISPLAY INVISIBLE (-7525 3350);
FORCEPROP 1 LAST PACK_TYPE RCL_GP
R 1
J 0
(-7525 3350);
DISPLAY 0.617021 (-7525 3350);
PAINT GREEN (-7525 3350);
DISPLAY INVISIBLE (-7525 3350);
FORCEPROP 1 LAST PART_NUMBER 64.12005.6DL
R 1
J 0
(-7525 3350);
DISPLAY 0.617021 (-7525 3350);
PAINT GREEN (-7525 3350);
DISPLAY INVISIBLE (-7525 3350);
FORCEPROP 1 LAST CDS_LMAN_SYM_OUTLINE -50,75,50,-75
R 1
J 0
(-7525 3350);
DISPLAY 0.468085 (-7525 3350);
PAINT GREEN (-7525 3350);
DISPLAY INVISIBLE (-7525 3350);
FORCEPROP 2 LAST CDS_LIB w_hdl
J 0
(-7525 3350);
PAINT MONO (-7525 3350);
DISPLAY INVISIBLE (-7525 3350);
FORCEADD 120R2F-GP..1
R 1
(-7525 3300);
FORCEPROP 1 LAST LOCATION R25W21
J 0
(-7875 3300);
DISPLAY 0.617021 (-7875 3300);
PAINT GREEN (-7875 3300);
FORCEPROP 1 LAST VALUE 120R2F-GP
J 0
(-7325 3300);
DISPLAY 0.617021 (-7325 3300);
PAINT GREEN (-7325 3300);
FORCEPROP 1 LAST PATH I185
R 1
J 0
(-7525 3300);
DISPLAY 0.617021 (-7525 3300);
PAINT GREEN (-7525 3300);
DISPLAY INVISIBLE (-7525 3300);
FORCEPROP 1 LAST PACK_TYPE RCL_GP
R 1
J 0
(-7525 3300);
DISPLAY 0.617021 (-7525 3300);
PAINT GREEN (-7525 3300);
DISPLAY INVISIBLE (-7525 3300);
FORCEPROP 1 LAST PART_NUMBER 64.12005.6DL
R 1
J 0
(-7525 3300);
DISPLAY 0.617021 (-7525 3300);
PAINT GREEN (-7525 3300);
DISPLAY INVISIBLE (-7525 3300);
FORCEPROP 1 LAST CDS_LMAN_SYM_OUTLINE -50,75,50,-75
R 1
J 0
(-7525 3300);
DISPLAY 0.468085 (-7525 3300);
PAINT GREEN (-7525 3300);
DISPLAY INVISIBLE (-7525 3300);
FORCEPROP 2 LAST CDS_LIB w_hdl
J 0
(-7525 3300);
PAINT MONO (-7525 3300);
DISPLAY INVISIBLE (-7525 3300);
FORCEADD 120R2F-GP..1
R 1
(-6150 4300);
FORCEPROP 1 LAST LOCATION R25W27
J 0
(-6475 4300);
DISPLAY 0.617021 (-6475 4300);
PAINT GREEN (-6475 4300);
FORCEPROP 1 LAST VALUE 120R2F-GP
J 0
(-5925 4300);
DISPLAY 0.617021 (-5925 4300);
PAINT GREEN (-5925 4300);
FORCEPROP 1 LAST PATH I186
R 1
J 0
(-6150 4300);
DISPLAY 0.617021 (-6150 4300);
PAINT GREEN (-6150 4300);
DISPLAY INVISIBLE (-6150 4300);
FORCEPROP 1 LAST PACK_TYPE RCL_GP
R 1
J 0
(-6150 4300);
DISPLAY 0.617021 (-6150 4300);
PAINT GREEN (-6150 4300);
DISPLAY INVISIBLE (-6150 4300);
FORCEPROP 1 LAST PART_NUMBER 64.12005.6DL
R 1
J 0
(-6150 4300);
DISPLAY 0.617021 (-6150 4300);
PAINT GREEN (-6150 4300);
DISPLAY INVISIBLE (-6150 4300);
FORCEPROP 2 LAST CDS_LIB w_hdl
R 1
J 0
(-6150 4300);
PAINT MONO (-6150 4300);
DISPLAY INVISIBLE (-6150 4300);
FORCEPROP 1 LAST CDS_LMAN_SYM_OUTLINE -50,75,50,-75
R 1
J 0
(-6150 4300);
DISPLAY 0.468085 (-6150 4300);
PAINT GREEN (-6150 4300);
DISPLAY INVISIBLE (-6150 4300);
FORCEADD 120R2F-GP..1
R 1
(-6150 4250);
FORCEPROP 1 LAST LOCATION R25W28
J 0
(-6475 4250);
DISPLAY 0.617021 (-6475 4250);
PAINT GREEN (-6475 4250);
FORCEPROP 1 LAST VALUE 120R2F-GP
J 0
(-5925 4250);
DISPLAY 0.617021 (-5925 4250);
PAINT GREEN (-5925 4250);
FORCEPROP 1 LAST PATH I187
R 1
J 0
(-6150 4250);
DISPLAY 0.617021 (-6150 4250);
PAINT GREEN (-6150 4250);
DISPLAY INVISIBLE (-6150 4250);
FORCEPROP 1 LAST PACK_TYPE RCL_GP
R 1
J 0
(-6150 4250);
DISPLAY 0.617021 (-6150 4250);
PAINT GREEN (-6150 4250);
DISPLAY INVISIBLE (-6150 4250);
FORCEPROP 1 LAST PART_NUMBER 64.12005.6DL
R 1
J 0
(-6150 4250);
DISPLAY 0.617021 (-6150 4250);
PAINT GREEN (-6150 4250);
DISPLAY INVISIBLE (-6150 4250);
FORCEPROP 1 LAST CDS_LMAN_SYM_OUTLINE -50,75,50,-75
R 1
J 0
(-6150 4250);
DISPLAY 0.468085 (-6150 4250);
PAINT GREEN (-6150 4250);
DISPLAY INVISIBLE (-6150 4250);
FORCEPROP 2 LAST CDS_LIB w_hdl
J 0
(-6150 4250);
PAINT MONO (-6150 4250);
DISPLAY INVISIBLE (-6150 4250);
FORCEADD 120R2F-GP..1
R 1
(-6150 4150);
FORCEPROP 1 LAST LOCATION R25W30
J 0
(-6475 4150);
DISPLAY 0.617021 (-6475 4150);
PAINT GREEN (-6475 4150);
FORCEPROP 1 LAST VALUE 120R2F-GP
J 0
(-5925 4150);
DISPLAY 0.617021 (-5925 4150);
PAINT GREEN (-5925 4150);
FORCEPROP 1 LAST PATH I188
R 1
J 0
(-6150 4150);
DISPLAY 0.617021 (-6150 4150);
PAINT GREEN (-6150 4150);
DISPLAY INVISIBLE (-6150 4150);
FORCEPROP 1 LAST PACK_TYPE RCL_GP
R 1
J 0
(-6150 4150);
DISPLAY 0.617021 (-6150 4150);
PAINT GREEN (-6150 4150);
DISPLAY INVISIBLE (-6150 4150);
FORCEPROP 1 LAST PART_NUMBER 64.12005.6DL
R 1
J 0
(-6150 4150);
DISPLAY 0.617021 (-6150 4150);
PAINT GREEN (-6150 4150);
DISPLAY INVISIBLE (-6150 4150);
FORCEPROP 1 LAST CDS_LMAN_SYM_OUTLINE -50,75,50,-75
R 1
J 0
(-6150 4150);
DISPLAY 0.468085 (-6150 4150);
PAINT GREEN (-6150 4150);
DISPLAY INVISIBLE (-6150 4150);
FORCEPROP 2 LAST CDS_LIB w_hdl
J 0
(-6150 4150);
PAINT MONO (-6150 4150);
DISPLAY INVISIBLE (-6150 4150);
FORCEADD 120R2F-GP..1
R 1
(-6150 4200);
FORCEPROP 1 LAST LOCATION R25W29
J 0
(-6475 4200);
DISPLAY 0.617021 (-6475 4200);
PAINT GREEN (-6475 4200);
FORCEPROP 1 LAST VALUE 120R2F-GP
J 0
(-5925 4200);
DISPLAY 0.617021 (-5925 4200);
PAINT GREEN (-5925 4200);
FORCEPROP 1 LAST PATH I189
R 1
J 0
(-6150 4200);
DISPLAY 0.617021 (-6150 4200);
PAINT GREEN (-6150 4200);
DISPLAY INVISIBLE (-6150 4200);
FORCEPROP 1 LAST PACK_TYPE RCL_GP
R 1
J 0
(-6150 4200);
DISPLAY 0.617021 (-6150 4200);
PAINT GREEN (-6150 4200);
DISPLAY INVISIBLE (-6150 4200);
FORCEPROP 1 LAST PART_NUMBER 64.12005.6DL
R 1
J 0
(-6150 4200);
DISPLAY 0.617021 (-6150 4200);
PAINT GREEN (-6150 4200);
DISPLAY INVISIBLE (-6150 4200);
FORCEPROP 2 LAST CDS_LIB w_hdl
R 1
J 0
(-6150 4200);
PAINT MONO (-6150 4200);
DISPLAY INVISIBLE (-6150 4200);
FORCEPROP 1 LAST CDS_LMAN_SYM_OUTLINE -50,75,50,-75
R 1
J 0
(-6150 4200);
DISPLAY 0.468085 (-6150 4200);
PAINT GREEN (-6150 4200);
DISPLAY INVISIBLE (-6150 4200);
FORCEADD OFFPAGE..3
(-875 3300);
FORCEPROP 2 LAST $XR1 149 
J 0
(-541 3300);
DISPLAY 0.638298 (-541 3300);
PAINT MONO (-541 3300);
FORCEPROP 2 LAST $XR0 143 
J 0
(-661 3300);
DISPLAY 0.638298 (-661 3300);
PAINT MONO (-661 3300);
FORCEPROP 1 LAST COMMENT_BODY TRUE
J 0
(-925 3200);
DISPLAY 0.872340 (-925 3200);
PAINT GREEN (-925 3200);
DISPLAY INVISIBLE (-925 3200);
FORCEPROP 1 LAST OFFPAGE TRUE
J 0
(-550 3175);
DISPLAY 0.872340 (-550 3175);
PAINT GREEN (-550 3175);
DISPLAY INVISIBLE (-550 3175);
FORCEPROP 2 LAST CDS_LIB mstr_standard
J 0
(-875 3300);
PAINT MONO (-875 3300);
DISPLAY INVISIBLE (-875 3300);
FORCEPROP 2 LAST PATH I19
J 0
(-525 3350);
DISPLAY 1.021277 (-525 3350);
PAINT ORANGE (-525 3350);
DISPLAY INVISIBLE (-525 3350);
FORCEADD 120R2F-GP..1
R 1
(-6150 4100);
FORCEPROP 1 LAST LOCATION R25W31
J 0
(-6475 4100);
DISPLAY 0.617021 (-6475 4100);
PAINT GREEN (-6475 4100);
FORCEPROP 1 LAST VALUE 120R2F-GP
J 0
(-5925 4100);
DISPLAY 0.617021 (-5925 4100);
PAINT GREEN (-5925 4100);
FORCEPROP 1 LAST PATH I190
R 1
J 0
(-6150 4100);
DISPLAY 0.617021 (-6150 4100);
PAINT GREEN (-6150 4100);
DISPLAY INVISIBLE (-6150 4100);
FORCEPROP 1 LAST PACK_TYPE RCL_GP
R 1
J 0
(-6150 4100);
DISPLAY 0.617021 (-6150 4100);
PAINT GREEN (-6150 4100);
DISPLAY INVISIBLE (-6150 4100);
FORCEPROP 1 LAST PART_NUMBER 64.12005.6DL
R 1
J 0
(-6150 4100);
DISPLAY 0.617021 (-6150 4100);
PAINT GREEN (-6150 4100);
DISPLAY INVISIBLE (-6150 4100);
FORCEPROP 2 LAST CDS_LIB w_hdl
R 1
J 0
(-6150 4100);
PAINT MONO (-6150 4100);
DISPLAY INVISIBLE (-6150 4100);
FORCEPROP 1 LAST CDS_LMAN_SYM_OUTLINE -50,75,50,-75
R 1
J 0
(-6150 4100);
DISPLAY 0.468085 (-6150 4100);
PAINT GREEN (-6150 4100);
DISPLAY INVISIBLE (-6150 4100);
FORCEADD 120R2F-GP..1
R 1
(-6150 4050);
FORCEPROP 1 LAST LOCATION R25W32
J 0
(-6475 4050);
DISPLAY 0.617021 (-6475 4050);
PAINT GREEN (-6475 4050);
FORCEPROP 1 LAST VALUE 120R2F-GP
J 0
(-5925 4050);
DISPLAY 0.617021 (-5925 4050);
PAINT GREEN (-5925 4050);
FORCEPROP 1 LAST PATH I191
R 1
J 0
(-6150 4050);
DISPLAY 0.617021 (-6150 4050);
PAINT GREEN (-6150 4050);
DISPLAY INVISIBLE (-6150 4050);
FORCEPROP 1 LAST PACK_TYPE RCL_GP
R 1
J 0
(-6150 4050);
DISPLAY 0.617021 (-6150 4050);
PAINT GREEN (-6150 4050);
DISPLAY INVISIBLE (-6150 4050);
FORCEPROP 1 LAST PART_NUMBER 64.12005.6DL
R 1
J 0
(-6150 4050);
DISPLAY 0.617021 (-6150 4050);
PAINT GREEN (-6150 4050);
DISPLAY INVISIBLE (-6150 4050);
FORCEPROP 1 LAST CDS_LMAN_SYM_OUTLINE -50,75,50,-75
R 1
J 0
(-6150 4050);
DISPLAY 0.468085 (-6150 4050);
PAINT GREEN (-6150 4050);
DISPLAY INVISIBLE (-6150 4050);
FORCEPROP 2 LAST CDS_LIB w_hdl
J 0
(-6150 4050);
PAINT MONO (-6150 4050);
DISPLAY INVISIBLE (-6150 4050);
FORCEADD 120R2F-GP..1
R 1
(-6150 4000);
FORCEPROP 1 LAST LOCATION R25W33
J 0
(-6475 4000);
DISPLAY 0.617021 (-6475 4000);
PAINT GREEN (-6475 4000);
FORCEPROP 1 LAST VALUE 120R2F-GP
J 0
(-5925 4000);
DISPLAY 0.617021 (-5925 4000);
PAINT GREEN (-5925 4000);
FORCEPROP 1 LAST PATH I192
R 1
J 0
(-6150 4000);
DISPLAY 0.617021 (-6150 4000);
PAINT GREEN (-6150 4000);
DISPLAY INVISIBLE (-6150 4000);
FORCEPROP 1 LAST PACK_TYPE RCL_GP
R 1
J 0
(-6150 4000);
DISPLAY 0.617021 (-6150 4000);
PAINT GREEN (-6150 4000);
DISPLAY INVISIBLE (-6150 4000);
FORCEPROP 1 LAST PART_NUMBER 64.12005.6DL
R 1
J 0
(-6150 4000);
DISPLAY 0.617021 (-6150 4000);
PAINT GREEN (-6150 4000);
DISPLAY INVISIBLE (-6150 4000);
FORCEPROP 2 LAST CDS_LIB w_hdl
R 1
J 0
(-6150 4000);
PAINT MONO (-6150 4000);
DISPLAY INVISIBLE (-6150 4000);
FORCEPROP 1 LAST CDS_LMAN_SYM_OUTLINE -50,75,50,-75
R 1
J 0
(-6150 4000);
DISPLAY 0.468085 (-6150 4000);
PAINT GREEN (-6150 4000);
DISPLAY INVISIBLE (-6150 4000);
FORCEADD 120R2F-GP..1
R 1
(-6150 3950);
FORCEPROP 1 LAST LOCATION R25W34
J 0
(-6475 3950);
DISPLAY 0.617021 (-6475 3950);
PAINT GREEN (-6475 3950);
FORCEPROP 1 LAST VALUE 120R2F-GP
J 0
(-5925 3950);
DISPLAY 0.617021 (-5925 3950);
PAINT GREEN (-5925 3950);
FORCEPROP 1 LAST PATH I193
R 1
J 0
(-6150 3950);
DISPLAY 0.617021 (-6150 3950);
PAINT GREEN (-6150 3950);
DISPLAY INVISIBLE (-6150 3950);
FORCEPROP 1 LAST PACK_TYPE RCL_GP
R 1
J 0
(-6150 3950);
DISPLAY 0.617021 (-6150 3950);
PAINT GREEN (-6150 3950);
DISPLAY INVISIBLE (-6150 3950);
FORCEPROP 1 LAST PART_NUMBER 64.12005.6DL
R 1
J 0
(-6150 3950);
DISPLAY 0.617021 (-6150 3950);
PAINT GREEN (-6150 3950);
DISPLAY INVISIBLE (-6150 3950);
FORCEPROP 1 LAST CDS_LMAN_SYM_OUTLINE -50,75,50,-75
R 1
J 0
(-6150 3950);
DISPLAY 0.468085 (-6150 3950);
PAINT GREEN (-6150 3950);
DISPLAY INVISIBLE (-6150 3950);
FORCEPROP 2 LAST CDS_LIB w_hdl
J 0
(-6150 3950);
PAINT MONO (-6150 3950);
DISPLAY INVISIBLE (-6150 3950);
FORCEADD 120R2F-GP..1
R 1
(-6150 3900);
FORCEPROP 1 LAST LOCATION R25W35
J 0
(-6475 3900);
DISPLAY 0.617021 (-6475 3900);
PAINT GREEN (-6475 3900);
FORCEPROP 1 LAST VALUE 120R2F-GP
J 0
(-5925 3900);
DISPLAY 0.617021 (-5925 3900);
PAINT GREEN (-5925 3900);
FORCEPROP 1 LAST PATH I194
R 1
J 0
(-6150 3900);
DISPLAY 0.617021 (-6150 3900);
PAINT GREEN (-6150 3900);
DISPLAY INVISIBLE (-6150 3900);
FORCEPROP 1 LAST PACK_TYPE RCL_GP
R 1
J 0
(-6150 3900);
DISPLAY 0.617021 (-6150 3900);
PAINT GREEN (-6150 3900);
DISPLAY INVISIBLE (-6150 3900);
FORCEPROP 1 LAST PART_NUMBER 64.12005.6DL
R 1
J 0
(-6150 3900);
DISPLAY 0.617021 (-6150 3900);
PAINT GREEN (-6150 3900);
DISPLAY INVISIBLE (-6150 3900);
FORCEPROP 2 LAST CDS_LIB w_hdl
R 1
J 0
(-6150 3900);
PAINT MONO (-6150 3900);
DISPLAY INVISIBLE (-6150 3900);
FORCEPROP 1 LAST CDS_LMAN_SYM_OUTLINE -50,75,50,-75
R 1
J 0
(-6150 3900);
DISPLAY 0.468085 (-6150 3900);
PAINT GREEN (-6150 3900);
DISPLAY INVISIBLE (-6150 3900);
FORCEADD 120R2F-GP..1
R 1
(-6150 3850);
FORCEPROP 1 LAST LOCATION R25W36
J 0
(-6475 3850);
DISPLAY 0.617021 (-6475 3850);
PAINT GREEN (-6475 3850);
FORCEPROP 1 LAST VALUE 120R2F-GP
J 0
(-5925 3850);
DISPLAY 0.617021 (-5925 3850);
PAINT GREEN (-5925 3850);
FORCEPROP 1 LAST PATH I195
R 1
J 0
(-6150 3850);
DISPLAY 0.617021 (-6150 3850);
PAINT GREEN (-6150 3850);
DISPLAY INVISIBLE (-6150 3850);
FORCEPROP 1 LAST PACK_TYPE RCL_GP
R 1
J 0
(-6150 3850);
DISPLAY 0.617021 (-6150 3850);
PAINT GREEN (-6150 3850);
DISPLAY INVISIBLE (-6150 3850);
FORCEPROP 1 LAST PART_NUMBER 64.12005.6DL
R 1
J 0
(-6150 3850);
DISPLAY 0.617021 (-6150 3850);
PAINT GREEN (-6150 3850);
DISPLAY INVISIBLE (-6150 3850);
FORCEPROP 1 LAST CDS_LMAN_SYM_OUTLINE -50,75,50,-75
R 1
J 0
(-6150 3850);
DISPLAY 0.468085 (-6150 3850);
PAINT GREEN (-6150 3850);
DISPLAY INVISIBLE (-6150 3850);
FORCEPROP 2 LAST CDS_LIB w_hdl
J 0
(-6150 3850);
PAINT MONO (-6150 3850);
DISPLAY INVISIBLE (-6150 3850);
FORCEADD 120R2F-GP..1
R 1
(-6150 3800);
FORCEPROP 1 LAST LOCATION R25W37
J 0
(-6475 3800);
DISPLAY 0.617021 (-6475 3800);
PAINT GREEN (-6475 3800);
FORCEPROP 1 LAST VALUE 120R2F-GP
J 0
(-5925 3800);
DISPLAY 0.617021 (-5925 3800);
PAINT GREEN (-5925 3800);
FORCEPROP 1 LAST PATH I196
R 1
J 0
(-6150 3800);
DISPLAY 0.617021 (-6150 3800);
PAINT GREEN (-6150 3800);
DISPLAY INVISIBLE (-6150 3800);
FORCEPROP 1 LAST PACK_TYPE RCL_GP
R 1
J 0
(-6150 3800);
DISPLAY 0.617021 (-6150 3800);
PAINT GREEN (-6150 3800);
DISPLAY INVISIBLE (-6150 3800);
FORCEPROP 1 LAST PART_NUMBER 64.12005.6DL
R 1
J 0
(-6150 3800);
DISPLAY 0.617021 (-6150 3800);
PAINT GREEN (-6150 3800);
DISPLAY INVISIBLE (-6150 3800);
FORCEPROP 2 LAST CDS_LIB w_hdl
R 1
J 0
(-6150 3800);
PAINT MONO (-6150 3800);
DISPLAY INVISIBLE (-6150 3800);
FORCEPROP 1 LAST CDS_LMAN_SYM_OUTLINE -50,75,50,-75
R 1
J 0
(-6150 3800);
DISPLAY 0.468085 (-6150 3800);
PAINT GREEN (-6150 3800);
DISPLAY INVISIBLE (-6150 3800);
FORCEADD 120R2F-GP..1
R 1
(-6150 3750);
FORCEPROP 1 LAST LOCATION R25W38
J 0
(-6475 3750);
DISPLAY 0.617021 (-6475 3750);
PAINT GREEN (-6475 3750);
FORCEPROP 1 LAST VALUE 120R2F-GP
J 0
(-5925 3750);
DISPLAY 0.617021 (-5925 3750);
PAINT GREEN (-5925 3750);
FORCEPROP 1 LAST PATH I197
R 1
J 0
(-6150 3750);
DISPLAY 0.617021 (-6150 3750);
PAINT GREEN (-6150 3750);
DISPLAY INVISIBLE (-6150 3750);
FORCEPROP 1 LAST PACK_TYPE RCL_GP
R 1
J 0
(-6150 3750);
DISPLAY 0.617021 (-6150 3750);
PAINT GREEN (-6150 3750);
DISPLAY INVISIBLE (-6150 3750);
FORCEPROP 1 LAST PART_NUMBER 64.12005.6DL
R 1
J 0
(-6150 3750);
DISPLAY 0.617021 (-6150 3750);
PAINT GREEN (-6150 3750);
DISPLAY INVISIBLE (-6150 3750);
FORCEPROP 1 LAST CDS_LMAN_SYM_OUTLINE -50,75,50,-75
R 1
J 0
(-6150 3750);
DISPLAY 0.468085 (-6150 3750);
PAINT GREEN (-6150 3750);
DISPLAY INVISIBLE (-6150 3750);
FORCEPROP 2 LAST CDS_LIB w_hdl
J 0
(-6150 3750);
PAINT MONO (-6150 3750);
DISPLAY INVISIBLE (-6150 3750);
FORCEADD 120R2F-GP..1
R 1
(-6150 3700);
FORCEPROP 1 LAST LOCATION R25W39
J 0
(-6475 3700);
DISPLAY 0.617021 (-6475 3700);
PAINT GREEN (-6475 3700);
FORCEPROP 1 LAST VALUE 120R2F-GP
J 0
(-5925 3700);
DISPLAY 0.617021 (-5925 3700);
PAINT GREEN (-5925 3700);
FORCEPROP 1 LAST PATH I198
R 1
J 0
(-6150 3700);
DISPLAY 0.617021 (-6150 3700);
PAINT GREEN (-6150 3700);
DISPLAY INVISIBLE (-6150 3700);
FORCEPROP 1 LAST PACK_TYPE RCL_GP
R 1
J 0
(-6150 3700);
DISPLAY 0.617021 (-6150 3700);
PAINT GREEN (-6150 3700);
DISPLAY INVISIBLE (-6150 3700);
FORCEPROP 1 LAST PART_NUMBER 64.12005.6DL
R 1
J 0
(-6150 3700);
DISPLAY 0.617021 (-6150 3700);
PAINT GREEN (-6150 3700);
DISPLAY INVISIBLE (-6150 3700);
FORCEPROP 2 LAST CDS_LIB w_hdl
R 1
J 0
(-6150 3700);
PAINT MONO (-6150 3700);
DISPLAY INVISIBLE (-6150 3700);
FORCEPROP 1 LAST CDS_LMAN_SYM_OUTLINE -50,75,50,-75
R 1
J 0
(-6150 3700);
DISPLAY 0.468085 (-6150 3700);
PAINT GREEN (-6150 3700);
DISPLAY INVISIBLE (-6150 3700);
FORCEADD 120R2F-GP..1
R 1
(-6150 3600);
FORCEPROP 1 LAST LOCATION R25W41
J 0
(-6475 3600);
DISPLAY 0.617021 (-6475 3600);
PAINT GREEN (-6475 3600);
FORCEPROP 1 LAST VALUE 120R2F-GP
J 0
(-5925 3600);
DISPLAY 0.617021 (-5925 3600);
PAINT GREEN (-5925 3600);
FORCEPROP 1 LAST PATH I199
R 1
J 0
(-6150 3600);
DISPLAY 0.617021 (-6150 3600);
PAINT GREEN (-6150 3600);
DISPLAY INVISIBLE (-6150 3600);
FORCEPROP 1 LAST PACK_TYPE RCL_GP
R 1
J 0
(-6150 3600);
DISPLAY 0.617021 (-6150 3600);
PAINT GREEN (-6150 3600);
DISPLAY INVISIBLE (-6150 3600);
FORCEPROP 1 LAST PART_NUMBER 64.12005.6DL
R 1
J 0
(-6150 3600);
DISPLAY 0.617021 (-6150 3600);
PAINT GREEN (-6150 3600);
DISPLAY INVISIBLE (-6150 3600);
FORCEPROP 2 LAST CDS_LIB w_hdl
R 1
J 0
(-6150 3600);
PAINT MONO (-6150 3600);
DISPLAY INVISIBLE (-6150 3600);
FORCEPROP 1 LAST CDS_LMAN_SYM_OUTLINE -50,75,50,-75
R 1
J 0
(-6150 3600);
DISPLAY 0.468085 (-6150 3600);
PAINT GREEN (-6150 3600);
DISPLAY INVISIBLE (-6150 3600);
FORCEADD OFFPAGE..2
(-350 4600);
FORCEPROP 2 LAST $XR0 146 
J 0
(-161 4600);
DISPLAY 0.638298 (-161 4600);
PAINT MONO (-161 4600);
FORCEPROP 2 LAST $XR1 149 
J 0
(-161 4600);
DISPLAY 0.638298 (-161 4600);
PAINT MONO (-161 4600);
FORCEPROP 1 LAST COMMENT_BODY TRUE
J 0
(-395 4505);
DISPLAY 0.872340 (-395 4505);
PAINT GREEN (-395 4505);
DISPLAY INVISIBLE (-395 4505);
FORCEPROP 1 LAST OFFPAGE TRUE
J 0
(-25 4475);
DISPLAY 0.872340 (-25 4475);
PAINT GREEN (-25 4475);
DISPLAY INVISIBLE (-25 4475);
FORCEPROP 2 LAST CDS_LIB mstr_standard
J 0
(-350 4600);
PAINT ORANGE (-350 4600);
DISPLAY INVISIBLE (-350 4600);
FORCEPROP 2 LAST PATH I2
J 0
(-150 4650);
DISPLAY 1.021277 (-150 4650);
PAINT ORANGE (-150 4650);
DISPLAY INVISIBLE (-150 4650);
FORCEADD OFFPAGE..3
(-875 3250);
FORCEPROP 2 LAST $XR1 149 
J 0
(-541 3250);
DISPLAY 0.638298 (-541 3250);
PAINT MONO (-541 3250);
FORCEPROP 2 LAST $XR0 143 
J 0
(-661 3250);
DISPLAY 0.638298 (-661 3250);
PAINT MONO (-661 3250);
FORCEPROP 1 LAST COMMENT_BODY TRUE
J 0
(-925 3150);
DISPLAY 0.872340 (-925 3150);
PAINT GREEN (-925 3150);
DISPLAY INVISIBLE (-925 3150);
FORCEPROP 1 LAST OFFPAGE TRUE
J 0
(-550 3125);
DISPLAY 0.872340 (-550 3125);
PAINT GREEN (-550 3125);
DISPLAY INVISIBLE (-550 3125);
FORCEPROP 2 LAST CDS_LIB mstr_standard
J 0
(-875 3250);
PAINT MONO (-875 3250);
DISPLAY INVISIBLE (-875 3250);
FORCEPROP 2 LAST PATH I20
J 0
(-525 3300);
DISPLAY 1.021277 (-525 3300);
PAINT ORANGE (-525 3300);
DISPLAY INVISIBLE (-525 3300);
FORCEADD 120R2F-GP..1
R 1
(-6150 3650);
FORCEPROP 1 LAST LOCATION R25W40
J 0
(-6475 3650);
DISPLAY 0.617021 (-6475 3650);
PAINT GREEN (-6475 3650);
FORCEPROP 1 LAST VALUE 120R2F-GP
J 0
(-5925 3650);
DISPLAY 0.617021 (-5925 3650);
PAINT GREEN (-5925 3650);
FORCEPROP 1 LAST PATH I200
R 1
J 0
(-6150 3650);
DISPLAY 0.617021 (-6150 3650);
PAINT GREEN (-6150 3650);
DISPLAY INVISIBLE (-6150 3650);
FORCEPROP 1 LAST PACK_TYPE RCL_GP
R 1
J 0
(-6150 3650);
DISPLAY 0.617021 (-6150 3650);
PAINT GREEN (-6150 3650);
DISPLAY INVISIBLE (-6150 3650);
FORCEPROP 1 LAST PART_NUMBER 64.12005.6DL
R 1
J 0
(-6150 3650);
DISPLAY 0.617021 (-6150 3650);
PAINT GREEN (-6150 3650);
DISPLAY INVISIBLE (-6150 3650);
FORCEPROP 1 LAST CDS_LMAN_SYM_OUTLINE -50,75,50,-75
R 1
J 0
(-6150 3650);
DISPLAY 0.468085 (-6150 3650);
PAINT GREEN (-6150 3650);
DISPLAY INVISIBLE (-6150 3650);
FORCEPROP 2 LAST CDS_LIB w_hdl
J 0
(-6150 3650);
PAINT MONO (-6150 3650);
DISPLAY INVISIBLE (-6150 3650);
FORCEADD 120R2F-GP..1
R 1
(-6150 3550);
FORCEPROP 1 LAST LOCATION R25W42
J 0
(-6475 3550);
DISPLAY 0.617021 (-6475 3550);
PAINT GREEN (-6475 3550);
FORCEPROP 1 LAST VALUE 120R2F-GP
J 0
(-5925 3550);
DISPLAY 0.617021 (-5925 3550);
PAINT GREEN (-5925 3550);
FORCEPROP 1 LAST PATH I201
R 1
J 0
(-6150 3550);
DISPLAY 0.617021 (-6150 3550);
PAINT GREEN (-6150 3550);
DISPLAY INVISIBLE (-6150 3550);
FORCEPROP 1 LAST PACK_TYPE RCL_GP
R 1
J 0
(-6150 3550);
DISPLAY 0.617021 (-6150 3550);
PAINT GREEN (-6150 3550);
DISPLAY INVISIBLE (-6150 3550);
FORCEPROP 1 LAST PART_NUMBER 64.12005.6DL
R 1
J 0
(-6150 3550);
DISPLAY 0.617021 (-6150 3550);
PAINT GREEN (-6150 3550);
DISPLAY INVISIBLE (-6150 3550);
FORCEPROP 1 LAST CDS_LMAN_SYM_OUTLINE -50,75,50,-75
R 1
J 0
(-6150 3550);
DISPLAY 0.468085 (-6150 3550);
PAINT GREEN (-6150 3550);
DISPLAY INVISIBLE (-6150 3550);
FORCEPROP 2 LAST CDS_LIB w_hdl
J 0
(-6150 3550);
PAINT MONO (-6150 3550);
DISPLAY INVISIBLE (-6150 3550);
FORCEADD 120R2F-GP..1
R 1
(-6150 3500);
FORCEPROP 1 LAST LOCATION R25W43
J 0
(-6475 3500);
DISPLAY 0.617021 (-6475 3500);
PAINT GREEN (-6475 3500);
FORCEPROP 1 LAST VALUE 120R2F-GP
J 0
(-5925 3500);
DISPLAY 0.617021 (-5925 3500);
PAINT GREEN (-5925 3500);
FORCEPROP 1 LAST PATH I202
R 1
J 0
(-6150 3500);
DISPLAY 0.617021 (-6150 3500);
PAINT GREEN (-6150 3500);
DISPLAY INVISIBLE (-6150 3500);
FORCEPROP 1 LAST PACK_TYPE RCL_GP
R 1
J 0
(-6150 3500);
DISPLAY 0.617021 (-6150 3500);
PAINT GREEN (-6150 3500);
DISPLAY INVISIBLE (-6150 3500);
FORCEPROP 1 LAST PART_NUMBER 64.12005.6DL
R 1
J 0
(-6150 3500);
DISPLAY 0.617021 (-6150 3500);
PAINT GREEN (-6150 3500);
DISPLAY INVISIBLE (-6150 3500);
FORCEPROP 2 LAST CDS_LIB w_hdl
R 1
J 0
(-6150 3500);
PAINT MONO (-6150 3500);
DISPLAY INVISIBLE (-6150 3500);
FORCEPROP 1 LAST CDS_LMAN_SYM_OUTLINE -50,75,50,-75
R 1
J 0
(-6150 3500);
DISPLAY 0.468085 (-6150 3500);
PAINT GREEN (-6150 3500);
DISPLAY INVISIBLE (-6150 3500);
FORCEADD 120R2F-GP..1
R 1
(-6150 3450);
FORCEPROP 1 LAST LOCATION R25W44
J 0
(-6475 3450);
DISPLAY 0.617021 (-6475 3450);
PAINT GREEN (-6475 3450);
FORCEPROP 1 LAST VALUE 120R2F-GP
J 0
(-5925 3450);
DISPLAY 0.617021 (-5925 3450);
PAINT GREEN (-5925 3450);
FORCEPROP 1 LAST PATH I203
R 1
J 0
(-6150 3450);
DISPLAY 0.617021 (-6150 3450);
PAINT GREEN (-6150 3450);
DISPLAY INVISIBLE (-6150 3450);
FORCEPROP 1 LAST PACK_TYPE RCL_GP
R 1
J 0
(-6150 3450);
DISPLAY 0.617021 (-6150 3450);
PAINT GREEN (-6150 3450);
DISPLAY INVISIBLE (-6150 3450);
FORCEPROP 1 LAST PART_NUMBER 64.12005.6DL
R 1
J 0
(-6150 3450);
DISPLAY 0.617021 (-6150 3450);
PAINT GREEN (-6150 3450);
DISPLAY INVISIBLE (-6150 3450);
FORCEPROP 1 LAST CDS_LMAN_SYM_OUTLINE -50,75,50,-75
R 1
J 0
(-6150 3450);
DISPLAY 0.468085 (-6150 3450);
PAINT GREEN (-6150 3450);
DISPLAY INVISIBLE (-6150 3450);
FORCEPROP 2 LAST CDS_LIB w_hdl
J 0
(-6150 3450);
PAINT MONO (-6150 3450);
DISPLAY INVISIBLE (-6150 3450);
FORCEADD 120R2F-GP..1
R 1
(-6150 3400);
FORCEPROP 1 LAST LOCATION R25W45
J 0
(-6475 3400);
DISPLAY 0.617021 (-6475 3400);
PAINT GREEN (-6475 3400);
FORCEPROP 1 LAST VALUE 120R2F-GP
J 0
(-5925 3400);
DISPLAY 0.617021 (-5925 3400);
PAINT GREEN (-5925 3400);
FORCEPROP 1 LAST PATH I204
R 1
J 0
(-6150 3400);
DISPLAY 0.617021 (-6150 3400);
PAINT GREEN (-6150 3400);
DISPLAY INVISIBLE (-6150 3400);
FORCEPROP 1 LAST PACK_TYPE RCL_GP
R 1
J 0
(-6150 3400);
DISPLAY 0.617021 (-6150 3400);
PAINT GREEN (-6150 3400);
DISPLAY INVISIBLE (-6150 3400);
FORCEPROP 1 LAST PART_NUMBER 64.12005.6DL
R 1
J 0
(-6150 3400);
DISPLAY 0.617021 (-6150 3400);
PAINT GREEN (-6150 3400);
DISPLAY INVISIBLE (-6150 3400);
FORCEPROP 2 LAST CDS_LIB w_hdl
R 1
J 0
(-6150 3400);
PAINT MONO (-6150 3400);
DISPLAY INVISIBLE (-6150 3400);
FORCEPROP 1 LAST CDS_LMAN_SYM_OUTLINE -50,75,50,-75
R 1
J 0
(-6150 3400);
DISPLAY 0.468085 (-6150 3400);
PAINT GREEN (-6150 3400);
DISPLAY INVISIBLE (-6150 3400);
FORCEADD 120R2F-GP..1
R 1
(-6150 3350);
FORCEPROP 1 LAST LOCATION R25W46
J 0
(-6475 3350);
DISPLAY 0.617021 (-6475 3350);
PAINT GREEN (-6475 3350);
FORCEPROP 1 LAST VALUE 120R2F-GP
J 0
(-5925 3350);
DISPLAY 0.617021 (-5925 3350);
PAINT GREEN (-5925 3350);
FORCEPROP 1 LAST PATH I205
R 1
J 0
(-6150 3350);
DISPLAY 0.617021 (-6150 3350);
PAINT GREEN (-6150 3350);
DISPLAY INVISIBLE (-6150 3350);
FORCEPROP 1 LAST PACK_TYPE RCL_GP
R 1
J 0
(-6150 3350);
DISPLAY 0.617021 (-6150 3350);
PAINT GREEN (-6150 3350);
DISPLAY INVISIBLE (-6150 3350);
FORCEPROP 1 LAST PART_NUMBER 64.12005.6DL
R 1
J 0
(-6150 3350);
DISPLAY 0.617021 (-6150 3350);
PAINT GREEN (-6150 3350);
DISPLAY INVISIBLE (-6150 3350);
FORCEPROP 1 LAST CDS_LMAN_SYM_OUTLINE -50,75,50,-75
R 1
J 0
(-6150 3350);
DISPLAY 0.468085 (-6150 3350);
PAINT GREEN (-6150 3350);
DISPLAY INVISIBLE (-6150 3350);
FORCEPROP 2 LAST CDS_LIB w_hdl
J 0
(-6150 3350);
PAINT MONO (-6150 3350);
DISPLAY INVISIBLE (-6150 3350);
FORCEADD 120R2F-GP..1
R 1
(-6150 3300);
FORCEPROP 1 LAST LOCATION R25W47
J 0
(-6475 3300);
DISPLAY 0.617021 (-6475 3300);
PAINT GREEN (-6475 3300);
FORCEPROP 1 LAST VALUE 120R2F-GP
J 0
(-5925 3300);
DISPLAY 0.617021 (-5925 3300);
PAINT GREEN (-5925 3300);
FORCEPROP 1 LAST PATH I206
R 1
J 0
(-6150 3300);
DISPLAY 0.617021 (-6150 3300);
PAINT GREEN (-6150 3300);
DISPLAY INVISIBLE (-6150 3300);
FORCEPROP 1 LAST PACK_TYPE RCL_GP
R 1
J 0
(-6150 3300);
DISPLAY 0.617021 (-6150 3300);
PAINT GREEN (-6150 3300);
DISPLAY INVISIBLE (-6150 3300);
FORCEPROP 1 LAST PART_NUMBER 64.12005.6DL
R 1
J 0
(-6150 3300);
DISPLAY 0.617021 (-6150 3300);
PAINT GREEN (-6150 3300);
DISPLAY INVISIBLE (-6150 3300);
FORCEPROP 1 LAST CDS_LMAN_SYM_OUTLINE -50,75,50,-75
R 1
J 0
(-6150 3300);
DISPLAY 0.468085 (-6150 3300);
PAINT GREEN (-6150 3300);
DISPLAY INVISIBLE (-6150 3300);
FORCEPROP 2 LAST CDS_LIB w_hdl
J 0
(-6150 3300);
PAINT MONO (-6150 3300);
DISPLAY INVISIBLE (-6150 3300);
FORCEADD 120R2F-GP..1
R 1
(-6150 3250);
FORCEPROP 1 LAST LOCATION R25W48
J 0
(-6475 3250);
DISPLAY 0.617021 (-6475 3250);
PAINT GREEN (-6475 3250);
FORCEPROP 1 LAST VALUE 120R2F-GP
J 0
(-5925 3250);
DISPLAY 0.617021 (-5925 3250);
PAINT GREEN (-5925 3250);
FORCEPROP 1 LAST PATH I207
R 1
J 0
(-6150 3250);
DISPLAY 0.617021 (-6150 3250);
PAINT GREEN (-6150 3250);
DISPLAY INVISIBLE (-6150 3250);
FORCEPROP 1 LAST PACK_TYPE RCL_GP
R 1
J 0
(-6150 3250);
DISPLAY 0.617021 (-6150 3250);
PAINT GREEN (-6150 3250);
DISPLAY INVISIBLE (-6150 3250);
FORCEPROP 1 LAST PART_NUMBER 64.12005.6DL
R 1
J 0
(-6150 3250);
DISPLAY 0.617021 (-6150 3250);
PAINT GREEN (-6150 3250);
DISPLAY INVISIBLE (-6150 3250);
FORCEPROP 1 LAST CDS_LMAN_SYM_OUTLINE -50,75,50,-75
R 1
J 0
(-6150 3250);
DISPLAY 0.468085 (-6150 3250);
PAINT GREEN (-6150 3250);
DISPLAY INVISIBLE (-6150 3250);
FORCEPROP 2 LAST CDS_LIB w_hdl
J 0
(-6150 3250);
PAINT MONO (-6150 3250);
DISPLAY INVISIBLE (-6150 3250);
FORCEADD 120R2F-GP..1
R 1
(-6150 3200);
FORCEPROP 1 LAST LOCATION R25W49
J 0
(-6475 3200);
DISPLAY 0.617021 (-6475 3200);
PAINT GREEN (-6475 3200);
FORCEPROP 1 LAST VALUE 120R2F-GP
J 0
(-5925 3200);
DISPLAY 0.617021 (-5925 3200);
PAINT GREEN (-5925 3200);
FORCEPROP 1 LAST PATH I208
R 1
J 0
(-6150 3200);
DISPLAY 0.617021 (-6150 3200);
PAINT GREEN (-6150 3200);
DISPLAY INVISIBLE (-6150 3200);
FORCEPROP 1 LAST PACK_TYPE RCL_GP
R 1
J 0
(-6150 3200);
DISPLAY 0.617021 (-6150 3200);
PAINT GREEN (-6150 3200);
DISPLAY INVISIBLE (-6150 3200);
FORCEPROP 1 LAST PART_NUMBER 64.12005.6DL
R 1
J 0
(-6150 3200);
DISPLAY 0.617021 (-6150 3200);
PAINT GREEN (-6150 3200);
DISPLAY INVISIBLE (-6150 3200);
FORCEPROP 2 LAST CDS_LIB w_hdl
R 1
J 0
(-6150 3200);
PAINT MONO (-6150 3200);
DISPLAY INVISIBLE (-6150 3200);
FORCEPROP 1 LAST CDS_LMAN_SYM_OUTLINE -50,75,50,-75
R 1
J 0
(-6150 3200);
DISPLAY 0.468085 (-6150 3200);
PAINT GREEN (-6150 3200);
DISPLAY INVISIBLE (-6150 3200);
FORCEADD 120R2F-GP..1
R 1
(-6150 3150);
FORCEPROP 1 LAST LOCATION R25W50
J 0
(-6475 3150);
DISPLAY 0.617021 (-6475 3150);
PAINT GREEN (-6475 3150);
FORCEPROP 1 LAST VALUE 120R2F-GP
J 0
(-5925 3150);
DISPLAY 0.617021 (-5925 3150);
PAINT GREEN (-5925 3150);
FORCEPROP 1 LAST PATH I209
R 1
J 0
(-6150 3150);
DISPLAY 0.617021 (-6150 3150);
PAINT GREEN (-6150 3150);
DISPLAY INVISIBLE (-6150 3150);
FORCEPROP 1 LAST PACK_TYPE RCL_GP
R 1
J 0
(-6150 3150);
DISPLAY 0.617021 (-6150 3150);
PAINT GREEN (-6150 3150);
DISPLAY INVISIBLE (-6150 3150);
FORCEPROP 1 LAST PART_NUMBER 64.12005.6DL
R 1
J 0
(-6150 3150);
DISPLAY 0.617021 (-6150 3150);
PAINT GREEN (-6150 3150);
DISPLAY INVISIBLE (-6150 3150);
FORCEPROP 1 LAST CDS_LMAN_SYM_OUTLINE -50,75,50,-75
R 1
J 0
(-6150 3150);
DISPLAY 0.468085 (-6150 3150);
PAINT GREEN (-6150 3150);
DISPLAY INVISIBLE (-6150 3150);
FORCEPROP 2 LAST CDS_LIB w_hdl
J 0
(-6150 3150);
PAINT MONO (-6150 3150);
DISPLAY INVISIBLE (-6150 3150);
FORCEADD OFFPAGE..3
(-875 3400);
FORCEPROP 2 LAST $XR0 143 
J 0
(-661 3400);
DISPLAY 0.638298 (-661 3400);
PAINT MONO (-661 3400);
FORCEPROP 2 LAST $XR1 149 
J 0
(-541 3400);
DISPLAY 0.638298 (-541 3400);
PAINT MONO (-541 3400);
FORCEPROP 1 LAST COMMENT_BODY TRUE
J 0
(-925 3300);
DISPLAY 0.872340 (-925 3300);
PAINT GREEN (-925 3300);
DISPLAY INVISIBLE (-925 3300);
FORCEPROP 1 LAST OFFPAGE TRUE
J 0
(-550 3275);
DISPLAY 0.872340 (-550 3275);
PAINT GREEN (-550 3275);
DISPLAY INVISIBLE (-550 3275);
FORCEPROP 2 LAST CDS_LIB mstr_standard
J 0
(-875 3400);
PAINT MONO (-875 3400);
DISPLAY INVISIBLE (-875 3400);
FORCEPROP 2 LAST PATH I21
J 0
(-525 3450);
DISPLAY 1.021277 (-525 3450);
PAINT ORANGE (-525 3450);
DISPLAY INVISIBLE (-525 3450);
FORCEADD 120R2F-GP..1
R 1
(-6150 3100);
FORCEPROP 1 LAST LOCATION R25W51
J 0
(-6475 3100);
DISPLAY 0.617021 (-6475 3100);
PAINT GREEN (-6475 3100);
FORCEPROP 1 LAST VALUE 120R2F-GP
J 0
(-5925 3100);
DISPLAY 0.617021 (-5925 3100);
PAINT GREEN (-5925 3100);
FORCEPROP 1 LAST PATH I210
R 1
J 0
(-6150 3100);
DISPLAY 0.617021 (-6150 3100);
PAINT GREEN (-6150 3100);
DISPLAY INVISIBLE (-6150 3100);
FORCEPROP 1 LAST PACK_TYPE RCL_GP
R 1
J 0
(-6150 3100);
DISPLAY 0.617021 (-6150 3100);
PAINT GREEN (-6150 3100);
DISPLAY INVISIBLE (-6150 3100);
FORCEPROP 1 LAST PART_NUMBER 64.12005.6DL
R 1
J 0
(-6150 3100);
DISPLAY 0.617021 (-6150 3100);
PAINT GREEN (-6150 3100);
DISPLAY INVISIBLE (-6150 3100);
FORCEPROP 2 LAST CDS_LIB w_hdl
R 1
J 0
(-6150 3100);
PAINT MONO (-6150 3100);
DISPLAY INVISIBLE (-6150 3100);
FORCEPROP 1 LAST CDS_LMAN_SYM_OUTLINE -50,75,50,-75
R 1
J 0
(-6150 3100);
DISPLAY 0.468085 (-6150 3100);
PAINT GREEN (-6150 3100);
DISPLAY INVISIBLE (-6150 3100);
FORCEADD 120R2F-GP..1
R 1
(-6150 3050);
FORCEPROP 1 LAST LOCATION R25W52
J 0
(-6475 3050);
DISPLAY 0.617021 (-6475 3050);
PAINT GREEN (-6475 3050);
FORCEPROP 1 LAST VALUE 120R2F-GP
J 0
(-5925 3050);
DISPLAY 0.617021 (-5925 3050);
PAINT GREEN (-5925 3050);
FORCEPROP 1 LAST PATH I211
R 1
J 0
(-6150 3050);
DISPLAY 0.617021 (-6150 3050);
PAINT GREEN (-6150 3050);
DISPLAY INVISIBLE (-6150 3050);
FORCEPROP 2 LAST CDS_LIB w_hdl
J 0
(-6150 3050);
PAINT MONO (-6150 3050);
DISPLAY INVISIBLE (-6150 3050);
FORCEPROP 1 LAST CDS_LMAN_SYM_OUTLINE -50,75,50,-75
R 1
J 0
(-6150 3050);
DISPLAY 0.468085 (-6150 3050);
PAINT GREEN (-6150 3050);
DISPLAY INVISIBLE (-6150 3050);
FORCEPROP 1 LAST PART_NUMBER 64.12005.6DL
R 1
J 0
(-6150 3050);
DISPLAY 0.617021 (-6150 3050);
PAINT GREEN (-6150 3050);
DISPLAY INVISIBLE (-6150 3050);
FORCEPROP 1 LAST PACK_TYPE RCL_GP
R 1
J 0
(-6150 3050);
DISPLAY 0.617021 (-6150 3050);
PAINT GREEN (-6150 3050);
DISPLAY INVISIBLE (-6150 3050);
FORCEADD 120R2F-GP..1
R 4
(-3550 775);
FORCEPROP 1 LAST VALUE 120R2F-GP
J 0
(-3525 700);
DISPLAY 0.617021 (-3525 700);
PAINT GREEN (-3525 700);
FORCEPROP 1 LAST LOCATION R1T28
J 0
(-3500 750);
DISPLAY 0.617021 (-3500 750);
PAINT GREEN (-3500 750);
FORCEPROP 2 LAST CDS_LIB w_hdl
R 1
J 0
(-3550 775);
PAINT MONO (-3550 775);
DISPLAY INVISIBLE (-3550 775);
FORCEPROP 1 LAST CDS_LMAN_SYM_OUTLINE -50,75,50,-75
R 2
J 0
(-3550 775);
DISPLAY 0.468085 (-3550 775);
PAINT GREEN (-3550 775);
DISPLAY INVISIBLE (-3550 775);
FORCEPROP 1 LAST PART_NUMBER 64.12005.6DL
R 2
J 0
(-3550 775);
DISPLAY 0.617021 (-3550 775);
PAINT GREEN (-3550 775);
DISPLAY INVISIBLE (-3550 775);
FORCEPROP 1 LAST PACK_TYPE RCL_GP
R 2
J 0
(-3550 775);
DISPLAY 0.617021 (-3550 775);
PAINT GREEN (-3550 775);
DISPLAY INVISIBLE (-3550 775);
FORCEPROP 1 LAST PATH I212
R 2
J 0
(-3550 775);
DISPLAY 0.617021 (-3550 775);
PAINT GREEN (-3550 775);
DISPLAY INVISIBLE (-3550 775);
FORCEADD OFFPAGE..3
(-875 3450);
FORCEPROP 2 LAST $XR1 149 
J 0
(-541 3450);
DISPLAY 0.638298 (-541 3450);
PAINT MONO (-541 3450);
FORCEPROP 2 LAST $XR0 143 
J 0
(-661 3450);
DISPLAY 0.638298 (-661 3450);
PAINT MONO (-661 3450);
FORCEPROP 1 LAST COMMENT_BODY TRUE
J 0
(-925 3350);
DISPLAY 0.872340 (-925 3350);
PAINT GREEN (-925 3350);
DISPLAY INVISIBLE (-925 3350);
FORCEPROP 1 LAST OFFPAGE TRUE
J 0
(-550 3325);
DISPLAY 0.872340 (-550 3325);
PAINT GREEN (-550 3325);
DISPLAY INVISIBLE (-550 3325);
FORCEPROP 2 LAST CDS_LIB mstr_standard
J 0
(-875 3450);
PAINT MONO (-875 3450);
DISPLAY INVISIBLE (-875 3450);
FORCEPROP 2 LAST PATH I22
J 0
(-525 3500);
DISPLAY 1.021277 (-525 3500);
PAINT ORANGE (-525 3500);
DISPLAY INVISIBLE (-525 3500);
FORCEADD OFFPAGE..3
(-875 3050);
FORCEPROP 2 LAST $XR1 149 
J 0
(-541 3050);
DISPLAY 0.638298 (-541 3050);
PAINT MONO (-541 3050);
FORCEPROP 2 LAST $XR0 143 
J 0
(-661 3050);
DISPLAY 0.638298 (-661 3050);
PAINT MONO (-661 3050);
FORCEPROP 1 LAST COMMENT_BODY TRUE
J 0
(-925 2950);
DISPLAY 0.872340 (-925 2950);
PAINT GREEN (-925 2950);
DISPLAY INVISIBLE (-925 2950);
FORCEPROP 1 LAST OFFPAGE TRUE
J 0
(-550 2925);
DISPLAY 0.872340 (-550 2925);
PAINT GREEN (-550 2925);
DISPLAY INVISIBLE (-550 2925);
FORCEPROP 2 LAST CDS_LIB mstr_standard
J 0
(-875 3050);
PAINT MONO (-875 3050);
DISPLAY INVISIBLE (-875 3050);
FORCEPROP 2 LAST PATH I23
J 0
(-525 3100);
DISPLAY 1.021277 (-525 3100);
PAINT ORANGE (-525 3100);
DISPLAY INVISIBLE (-525 3100);
FORCEADD OFFPAGE..3
(-875 3100);
FORCEPROP 2 LAST $XR1 149 
J 0
(-541 3100);
DISPLAY 0.638298 (-541 3100);
PAINT MONO (-541 3100);
FORCEPROP 2 LAST $XR0 143 
J 0
(-661 3100);
DISPLAY 0.638298 (-661 3100);
PAINT MONO (-661 3100);
FORCEPROP 1 LAST COMMENT_BODY TRUE
J 0
(-925 3000);
DISPLAY 0.872340 (-925 3000);
PAINT GREEN (-925 3000);
DISPLAY INVISIBLE (-925 3000);
FORCEPROP 1 LAST OFFPAGE TRUE
J 0
(-550 2975);
DISPLAY 0.872340 (-550 2975);
PAINT GREEN (-550 2975);
DISPLAY INVISIBLE (-550 2975);
FORCEPROP 2 LAST CDS_LIB mstr_standard
J 0
(-875 3100);
PAINT MONO (-875 3100);
DISPLAY INVISIBLE (-875 3100);
FORCEPROP 2 LAST PATH I24
J 0
(-525 3150);
DISPLAY 1.021277 (-525 3150);
PAINT ORANGE (-525 3150);
DISPLAY INVISIBLE (-525 3150);
FORCEADD OFFPAGE..3
(-875 3150);
FORCEPROP 2 LAST $XR1 149 
J 0
(-541 3150);
DISPLAY 0.638298 (-541 3150);
PAINT MONO (-541 3150);
FORCEPROP 2 LAST $XR0 143 
J 0
(-661 3150);
DISPLAY 0.638298 (-661 3150);
PAINT MONO (-661 3150);
FORCEPROP 1 LAST COMMENT_BODY TRUE
J 0
(-925 3050);
DISPLAY 0.872340 (-925 3050);
PAINT GREEN (-925 3050);
DISPLAY INVISIBLE (-925 3050);
FORCEPROP 1 LAST OFFPAGE TRUE
J 0
(-550 3025);
DISPLAY 0.872340 (-550 3025);
PAINT GREEN (-550 3025);
DISPLAY INVISIBLE (-550 3025);
FORCEPROP 2 LAST CDS_LIB mstr_standard
J 0
(-875 3150);
PAINT MONO (-875 3150);
DISPLAY INVISIBLE (-875 3150);
FORCEPROP 2 LAST PATH I25
J 0
(-525 3200);
DISPLAY 1.021277 (-525 3200);
PAINT ORANGE (-525 3200);
DISPLAY INVISIBLE (-525 3200);
FORCEADD OFFPAGE..3
(-875 2800);
FORCEPROP 2 LAST $XR1 149 
J 0
(-541 2800);
DISPLAY 0.638298 (-541 2800);
PAINT MONO (-541 2800);
FORCEPROP 2 LAST $XR0 146 
J 0
(-661 2800);
DISPLAY 0.638298 (-661 2800);
PAINT MONO (-661 2800);
FORCEPROP 1 LAST COMMENT_BODY TRUE
J 0
(-925 2700);
DISPLAY 0.872340 (-925 2700);
PAINT GREEN (-925 2700);
DISPLAY INVISIBLE (-925 2700);
FORCEPROP 1 LAST OFFPAGE TRUE
J 0
(-550 2675);
DISPLAY 0.872340 (-550 2675);
PAINT GREEN (-550 2675);
DISPLAY INVISIBLE (-550 2675);
FORCEPROP 2 LAST CDS_LIB mstr_standard
J 0
(-875 2800);
PAINT MONO (-875 2800);
DISPLAY INVISIBLE (-875 2800);
FORCEPROP 2 LAST PATH I26
J 0
(-525 2850);
DISPLAY 1.021277 (-525 2850);
PAINT ORANGE (-525 2850);
DISPLAY INVISIBLE (-525 2850);
FORCEADD OFFPAGE..3
(-875 2850);
FORCEPROP 2 LAST $XR1 149 
J 0
(-541 2850);
DISPLAY 0.638298 (-541 2850);
PAINT MONO (-541 2850);
FORCEPROP 2 LAST $XR0 146 
J 0
(-661 2850);
DISPLAY 0.638298 (-661 2850);
PAINT MONO (-661 2850);
FORCEPROP 1 LAST COMMENT_BODY TRUE
J 0
(-925 2750);
DISPLAY 0.872340 (-925 2750);
PAINT GREEN (-925 2750);
DISPLAY INVISIBLE (-925 2750);
FORCEPROP 1 LAST OFFPAGE TRUE
J 0
(-550 2725);
DISPLAY 0.872340 (-550 2725);
PAINT GREEN (-550 2725);
DISPLAY INVISIBLE (-550 2725);
FORCEPROP 2 LAST CDS_LIB mstr_standard
J 0
(-875 2850);
PAINT MONO (-875 2850);
DISPLAY INVISIBLE (-875 2850);
FORCEPROP 2 LAST PATH I27
J 0
(-525 2900);
DISPLAY 1.021277 (-525 2900);
PAINT ORANGE (-525 2900);
DISPLAY INVISIBLE (-525 2900);
FORCEADD OFFPAGE..3
(-875 2900);
FORCEPROP 2 LAST $XR0 143 
J 0
(-661 2900);
DISPLAY 0.638298 (-661 2900);
PAINT MONO (-661 2900);
FORCEPROP 2 LAST $XR1 149 
J 0
(-541 2900);
DISPLAY 0.638298 (-541 2900);
PAINT MONO (-541 2900);
FORCEPROP 1 LAST COMMENT_BODY TRUE
J 0
(-925 2800);
DISPLAY 0.872340 (-925 2800);
PAINT GREEN (-925 2800);
DISPLAY INVISIBLE (-925 2800);
FORCEPROP 1 LAST OFFPAGE TRUE
J 0
(-550 2775);
DISPLAY 0.872340 (-550 2775);
PAINT GREEN (-550 2775);
DISPLAY INVISIBLE (-550 2775);
FORCEPROP 2 LAST CDS_LIB mstr_standard
J 0
(-875 2900);
PAINT MONO (-875 2900);
DISPLAY INVISIBLE (-875 2900);
FORCEPROP 2 LAST PATH I28
J 0
(-525 2950);
DISPLAY 1.021277 (-525 2950);
PAINT ORANGE (-525 2950);
DISPLAY INVISIBLE (-525 2950);
FORCEADD OFFPAGE..3
(-875 2950);
FORCEPROP 2 LAST $XR0 143 
J 0
(-661 2950);
DISPLAY 0.638298 (-661 2950);
PAINT MONO (-661 2950);
FORCEPROP 2 LAST $XR1 149 
J 0
(-541 2950);
DISPLAY 0.638298 (-541 2950);
PAINT MONO (-541 2950);
FORCEPROP 1 LAST COMMENT_BODY TRUE
J 0
(-925 2850);
DISPLAY 0.872340 (-925 2850);
PAINT GREEN (-925 2850);
DISPLAY INVISIBLE (-925 2850);
FORCEPROP 1 LAST OFFPAGE TRUE
J 0
(-550 2825);
DISPLAY 0.872340 (-550 2825);
PAINT GREEN (-550 2825);
DISPLAY INVISIBLE (-550 2825);
FORCEPROP 2 LAST CDS_LIB mstr_standard
J 0
(-875 2950);
PAINT MONO (-875 2950);
DISPLAY INVISIBLE (-875 2950);
FORCEPROP 2 LAST PATH I29
J 0
(-525 3000);
DISPLAY 1.021277 (-525 3000);
PAINT ORANGE (-525 3000);
DISPLAY INVISIBLE (-525 3000);
FORCEADD OFFPAGE..3
(-875 4000);
FORCEPROP 2 LAST $XR0 143 
J 0
(-661 4000);
DISPLAY 0.638298 (-661 4000);
PAINT MONO (-661 4000);
FORCEPROP 2 LAST $XR1 149 
J 0
(-541 4000);
DISPLAY 0.638298 (-541 4000);
PAINT MONO (-541 4000);
FORCEPROP 1 LAST COMMENT_BODY TRUE
J 0
(-925 3900);
DISPLAY 0.872340 (-925 3900);
PAINT GREEN (-925 3900);
DISPLAY INVISIBLE (-925 3900);
FORCEPROP 1 LAST OFFPAGE TRUE
J 0
(-550 3875);
DISPLAY 0.872340 (-550 3875);
PAINT GREEN (-550 3875);
DISPLAY INVISIBLE (-550 3875);
FORCEPROP 2 LAST PATH I3
J 0
(-525 4050);
DISPLAY 1.021277 (-525 4050);
PAINT ORANGE (-525 4050);
DISPLAY INVISIBLE (-525 4050);
FORCEPROP 2 LAST CDS_LIB mstr_standard
J 0
(-875 4000);
PAINT MONO (-875 4000);
DISPLAY INVISIBLE (-875 4000);
FORCEADD OFFPAGE..3
(-875 2600);
FORCEPROP 2 LAST $XR0 143 
J 0
(-661 2600);
DISPLAY 0.638298 (-661 2600);
PAINT MONO (-661 2600);
FORCEPROP 2 LAST $XR1 149 
J 0
(-541 2600);
DISPLAY 0.638298 (-541 2600);
PAINT MONO (-541 2600);
FORCEPROP 1 LAST COMMENT_BODY TRUE
J 0
(-925 2500);
DISPLAY 0.872340 (-925 2500);
PAINT GREEN (-925 2500);
DISPLAY INVISIBLE (-925 2500);
FORCEPROP 1 LAST OFFPAGE TRUE
J 0
(-550 2475);
DISPLAY 0.872340 (-550 2475);
PAINT GREEN (-550 2475);
DISPLAY INVISIBLE (-550 2475);
FORCEPROP 2 LAST PATH I30
J 0
(-525 2650);
DISPLAY 1.021277 (-525 2650);
PAINT ORANGE (-525 2650);
DISPLAY INVISIBLE (-525 2650);
FORCEPROP 2 LAST CDS_LIB mstr_standard
J 0
(-875 2600);
PAINT MONO (-875 2600);
DISPLAY INVISIBLE (-875 2600);
FORCEADD OFFPAGE..3
(-875 2700);
FORCEPROP 2 LAST $XR0 143 
J 0
(-661 2700);
DISPLAY 0.638298 (-661 2700);
PAINT MONO (-661 2700);
FORCEPROP 2 LAST $XR1 149 
J 0
(-541 2700);
DISPLAY 0.638298 (-541 2700);
PAINT MONO (-541 2700);
FORCEPROP 1 LAST COMMENT_BODY TRUE
J 0
(-925 2600);
DISPLAY 0.872340 (-925 2600);
PAINT GREEN (-925 2600);
DISPLAY INVISIBLE (-925 2600);
FORCEPROP 1 LAST OFFPAGE TRUE
J 0
(-550 2575);
DISPLAY 0.872340 (-550 2575);
PAINT GREEN (-550 2575);
DISPLAY INVISIBLE (-550 2575);
FORCEPROP 2 LAST PATH I31
J 0
(-525 2750);
DISPLAY 1.021277 (-525 2750);
PAINT ORANGE (-525 2750);
DISPLAY INVISIBLE (-525 2750);
FORCEPROP 2 LAST CDS_LIB mstr_standard
J 0
(-875 2700);
PAINT MONO (-875 2700);
DISPLAY INVISIBLE (-875 2700);
FORCEADD OFFPAGE..3
(-825 2400);
FORCEPROP 2 LAST $XR0 149 
J 0
(-611 2400);
DISPLAY 0.638298 (-611 2400);
PAINT MONO (-611 2400);
FORCEPROP 1 LAST COMMENT_BODY TRUE
J 0
(-875 2300);
DISPLAY 0.872340 (-875 2300);
PAINT GREEN (-875 2300);
DISPLAY INVISIBLE (-875 2300);
FORCEPROP 1 LAST OFFPAGE TRUE
J 0
(-500 2275);
DISPLAY 0.872340 (-500 2275);
PAINT GREEN (-500 2275);
DISPLAY INVISIBLE (-500 2275);
FORCEPROP 2 LAST CDS_LIB mstr_standard
J 0
(-825 2400);
PAINT MONO (-825 2400);
DISPLAY INVISIBLE (-825 2400);
FORCEPROP 2 LAST PATH I32
J 0
(-600 2450);
DISPLAY 1.021277 (-600 2450);
PAINT ORANGE (-600 2450);
DISPLAY INVISIBLE (-600 2450);
FORCEADD GND..1
(-1150 1050);
FORCEPROP 3 LASTPIN (-1150 1100) SIG_NAME GND\g
J 0
(-1140 1110);
DISPLAY 0.659574 (-1140 1110);
PAINT MONO (-1140 1110);
DISPLAY INVISIBLE (-1140 1110);
FORCEPROP 1 LAST HDL_POWER GND
J 0
(-1150 1200);
DISPLAY 0.872340 (-1150 1200);
PAINT GREEN (-1150 1200);
DISPLAY INVISIBLE (-1150 1200);
FORCEPROP 1 LAST BODY_TYPE PLUMBING
J 0
(-1195 1007);
DISPLAY 0.340426 (-1195 1007);
PAINT GREEN (-1195 1007);
DISPLAY INVISIBLE (-1195 1007);
FORCEPROP 1 LAST VOLTAGE 0.0V
J 0
(-1195 1007);
DISPLAY 0.340426 (-1195 1007);
PAINT GREEN (-1195 1007);
DISPLAY INVISIBLE (-1195 1007);
FORCEPROP 1 LAST SIZE 1B
J 0
(-1075 1000);
DISPLAY 0.872340 (-1075 1000);
PAINT AQUA (-1075 1000);
DISPLAY INVISIBLE (-1075 1000);
FORCEPROP 2 LAST CDS_LIB mstr_symbols
J 0
(-1150 1050);
PAINT MONO (-1150 1050);
DISPLAY INVISIBLE (-1150 1050);
FORCEPROP 1 LAST PATH I33
J 0
(-1075 1050);
DISPLAY 0.872340 (-1075 1050);
PAINT AQUA (-1075 1050);
DISPLAY INVISIBLE (-1075 1050);
FORCEADD TTL1G07_A..1
(-2475 4600);
FORCEPROP 1 LAST VALUE 74LVC1G07
J 1
(-2475 4700);
DISPLAY 0.617021 (-2475 4700);
PAINT SKYBLUE (-2475 4700);
FORCEPROP 1 LAST LOCATION U9F3
J 0
(-2525 4800);
DISPLAY 0.617021 (-2525 4800);
PAINT AQUA (-2525 4800);
FORCEPROP 2 LASTPIN (-2325 4600) $PN 4
J 0
(-2315 4610);
DISPLAY 0.617021 (-2315 4610);
PAINT ORANGE (-2315 4610);
FORCEPROP 2 LASTPIN (-2575 4600) $PN 2
J 2
(-2585 4610);
DISPLAY 0.617021 (-2585 4610);
PAINT ORANGE (-2585 4610);
FORCEPROP 1 LAST POWER_GROUP VCC=P3V3_STBY;GND=GND
J 1
(-2525 4410);
DISPLAY 0.617021 (-2525 4410);
PAINT ORANGE (-2525 4410);
FORCEPROP 1 LAST PART_NUMBER C88419-001
J 0
(-2525 4465);
DISPLAY 0.617021 (-2525 4465);
PAINT BLUE (-2525 4465);
FORCEPROP 1 LAST MATERIAL IC
J 0
(-2525 4750);
DISPLAY 0.617021 (-2525 4750);
PAINT SKYBLUE (-2525 4750);
FORCEPROP 1 LAST PACK_TYPE SOP
J 0
(-2525 4850);
DISPLAY 0.978723 (-2525 4850);
PAINT SKYBLUE (-2525 4850);
DISPLAY INVISIBLE (-2525 4850);
FORCEPROP 2 LAST CDS_LIB mstr_ttl
J 0
(-2475 4600);
PAINT ORANGE (-2475 4600);
DISPLAY INVISIBLE (-2475 4600);
FORCEPROP 2 LAST SEC_TYPE SOP
J 0
(-2525 4850);
DISPLAY 1.021277 (-2525 4850);
PAINT ORANGE (-2525 4850);
DISPLAY INVISIBLE (-2525 4850);
FORCEPROP 2 LAST SEC 1
J 0
(-2525 4850);
DISPLAY 0.680851 (-2525 4850);
PAINT MONO (-2525 4850);
DISPLAY INVISIBLE (-2525 4850);
FORCEPROP 2 LAST CDS_LOCATION U9F3
J 0
(-2525 4800);
DISPLAY 0.617021 (-2525 4800);
PAINT AQUA (-2525 4800);
DISPLAY INVISIBLE (-2525 4800);
FORCEPROP 0 LAST ROOM BMC_MEMORY
J 0
(-2525 4900);
DISPLAY 1.021277 (-2525 4900);
PAINT ORANGE (-2525 4900);
DISPLAY INVISIBLE (-2525 4900);
FORCEPROP 0 LAST CDS_SEC 1
J 0
(-2525 4850);
PAINT MONO (-2525 4850);
DISPLAY INVISIBLE (-2525 4850);
FORCEPROP 1 LAST PATH I34
J 0
(-2425 4650);
DISPLAY 0.978723 (-2425 4650);
PAINT WHITE (-2425 4650);
DISPLAY INVISIBLE (-2425 4650);
FORCEADD W_VCC_CIRCLE..1
(-2600 4050);
FORCEPROP 3 LASTPIN (-2600 4050) SIG_NAME P1V2_AUX_BMC\g
J 0
(-2590 4060);
DISPLAY 0.659574 (-2590 4060);
PAINT MONO (-2590 4060);
DISPLAY INVISIBLE (-2590 4060);
FORCEPROP 1 LAST HDL_POWER P1V2_AUX_BMC
J 1
(-2579 4125);
DISPLAY 0.872340 (-2579 4125);
PAINT ORANGE (-2579 4125);
FORCEPROP 1 LAST BODY_TYPE PLUMBING
J 0
(-2588 4044);
DISPLAY 0.340426 (-2588 4044);
PAINT GREEN (-2588 4044);
DISPLAY INVISIBLE (-2588 4044);
FORCEPROP 2 LAST CDS_LIB w_power
J 0
(-2600 4050);
PAINT MONO (-2600 4050);
DISPLAY INVISIBLE (-2600 4050);
FORCEPROP 1 LAST CDS_LMAN_SYM_OUTLINE -100,100,100,-100
J 0
(-2600 4050);
DISPLAY 0.468085 (-2600 4050);
PAINT GREEN (-2600 4050);
DISPLAY INVISIBLE (-2600 4050);
FORCEPROP 1 LAST PATH I35
J 0
(-2600 4050);
DISPLAY 0.617021 (-2600 4050);
PAINT GREEN (-2600 4050);
DISPLAY INVISIBLE (-2600 4050);
FORCEADD OFFPAGE..1
(-3350 4600);
FORCEPROP 2 LAST $XR0 157 
J 0
(-3632 4600);
DISPLAY 0.638298 (-3632 4600);
PAINT MONO (-3632 4600);
FORCEPROP 1 LAST COMMENT_BODY TRUE
J 0
(-3225 4500);
DISPLAY 0.872340 (-3225 4500);
PAINT GREEN (-3225 4500);
DISPLAY INVISIBLE (-3225 4500);
FORCEPROP 1 LAST OFFPAGE TRUE
J 0
(-3025 4475);
DISPLAY 0.872340 (-3025 4475);
PAINT GREEN (-3025 4475);
DISPLAY INVISIBLE (-3025 4475);
FORCEPROP 2 LAST CDS_LIB mstr_standard
J 0
(-3350 4600);
PAINT ORANGE (-3350 4600);
DISPLAY INVISIBLE (-3350 4600);
FORCEPROP 2 LAST PATH I36
J 0
(-3625 4650);
DISPLAY 1.021277 (-3625 4650);
PAINT ORANGE (-3625 4650);
DISPLAY INVISIBLE (-3625 4650);
FORCEADD CAP..1
(-4025 4700);
FORCEPROP 1 LAST MATERIAL COG
J 0
(-3975 4600);
DISPLAY 0.617021 (-3975 4600);
PAINT SKYBLUE (-3975 4600);
FORCEPROP 1 LAST TOLERANCE 5%
J 0
(-3975 4650);
DISPLAY 0.617021 (-3975 4650);
PAINT SKYBLUE (-3975 4650);
FORCEPROP 1 LAST PACK_TYPE 0402LF
J 0
(-3975 4575);
DISPLAY 0.617021 (-3975 4575);
PAINT SKYBLUE (-3975 4575);
FORCEPROP 1 LAST PART_NUMBER A36095-026
R 1
J 0
(-4100 4500);
DISPLAY 0.617021 (-4100 4500);
PAINT BLUE (-4100 4500);
FORCEPROP 1 LAST VALUE 100.0PF
J 0
(-3975 4750);
DISPLAY 0.617021 (-3975 4750);
PAINT SKYBLUE (-3975 4750);
FORCEPROP 1 LAST VOLTAGE 50V
J 0
(-3975 4700);
DISPLAY 0.617021 (-3975 4700);
PAINT SKYBLUE (-3975 4700);
FORCEPROP 1 LAST LOCATION C25W16
J 0
(-3975 4800);
DISPLAY 0.617021 (-3975 4800);
PAINT AQUA (-3975 4800);
FORCEPROP 2 LAST CDS_LIB mstr_discrete
J 0
(-4025 4700);
PAINT MONO (-4025 4700);
DISPLAY INVISIBLE (-4025 4700);
FORCEPROP 0 LAST ROOM BMC
J 0
(-3975 4850);
DISPLAY 1.021277 (-3975 4850);
PAINT ORANGE (-3975 4850);
DISPLAY INVISIBLE (-3975 4850);
FORCEPROP 0 LAST BOM_COST SM_CONTROLLER
J 0
(-3975 4900);
DISPLAY 1.021277 (-3975 4900);
PAINT ORANGE (-3975 4900);
DISPLAY INVISIBLE (-3975 4900);
FORCEPROP 1 LAST PATH I37
J 0
(-3975 4850);
DISPLAY 0.978723 (-3975 4850);
PAINT WHITE (-3975 4850);
DISPLAY INVISIBLE (-3975 4850);
FORCEPROP 1 LASTPIN (-4025 4600) $PN 2
J 0
(-4015 4580);
DISPLAY 0.787234 (-4015 4580);
PAINT ORANGE (-4015 4580);
DISPLAY INVISIBLE (-4015 4580);
FORCEPROP 1 LASTPIN (-4025 4800) $PN 1
J 0
(-4015 4780);
DISPLAY 0.787234 (-4015 4780);
PAINT ORANGE (-4015 4780);
DISPLAY INVISIBLE (-4015 4780);
FORCEADD SC1U16V3KX-2GP..1
(-4450 4700);
FORCEPROP 1 LAST VALUE SC1U16V3KX-2GP
J 0
(-4425 4625);
DISPLAY 0.617021 (-4425 4625);
PAINT GREEN (-4425 4625);
FORCEPROP 1 LAST LOCATION C25W17
J 0
(-4425 4730);
DISPLAY 0.617021 (-4425 4730);
PAINT GREEN (-4425 4730);
FORCEPROP 2 LAST CDS_LIB w_hdl
J 0
(-4450 4700);
PAINT MONO (-4450 4700);
DISPLAY INVISIBLE (-4450 4700);
FORCEPROP 1 LAST CDS_LMAN_SYM_OUTLINE -50,25,50,-25
J 0
(-4450 4700);
DISPLAY 0.468085 (-4450 4700);
PAINT GREEN (-4450 4700);
DISPLAY INVISIBLE (-4450 4700);
FORCEPROP 1 LAST PART_NUMBER 78.10521.5BL
J 0
(-4450 4700);
DISPLAY 0.617021 (-4450 4700);
PAINT GREEN (-4450 4700);
DISPLAY INVISIBLE (-4450 4700);
FORCEPROP 1 LAST PACK_TYPE SMD-BCG
J 0
(-4450 4700);
DISPLAY 0.617021 (-4450 4700);
PAINT GREEN (-4450 4700);
DISPLAY INVISIBLE (-4450 4700);
FORCEPROP 1 LAST PATH I38
J 0
(-4450 4700);
DISPLAY 0.617021 (-4450 4700);
PAINT GREEN (-4450 4700);
DISPLAY INVISIBLE (-4450 4700);
FORCEADD SCD1U16V2KX-3GP..1
(-3050 3075);
FORCEPROP 1 LAST VALUE SCD1U16V2KX-3GP
J 0
(-3025 3025);
DISPLAY 0.617021 (-3025 3025);
PAINT GREEN (-3025 3025);
FORCEPROP 1 LAST LOCATION C25W15
J 0
(-3025 3105);
DISPLAY 0.617021 (-3025 3105);
PAINT GREEN (-3025 3105);
FORCEPROP 2 LAST CDS_LIB w_hdl
J 0
(-3050 3075);
PAINT MONO (-3050 3075);
DISPLAY INVISIBLE (-3050 3075);
FORCEPROP 1 LAST CDS_LMAN_SYM_OUTLINE -50,25,50,-25
J 0
(-3050 3075);
DISPLAY 0.468085 (-3050 3075);
PAINT GREEN (-3050 3075);
DISPLAY INVISIBLE (-3050 3075);
FORCEPROP 1 LAST PACK_TYPE SMD-BCG
J 0
(-3050 3075);
DISPLAY 0.617021 (-3050 3075);
PAINT GREEN (-3050 3075);
DISPLAY INVISIBLE (-3050 3075);
FORCEPROP 1 LAST PART_NUMBER 78.10421.2FL
J 0
(-3050 3075);
DISPLAY 0.617021 (-3050 3075);
PAINT GREEN (-3050 3075);
DISPLAY INVISIBLE (-3050 3075);
FORCEPROP 1 LAST PATH I39
J 0
(-3050 3075);
DISPLAY 0.617021 (-3050 3075);
PAINT GREEN (-3050 3075);
DISPLAY INVISIBLE (-3050 3075);
FORCEADD OFFPAGE..3
(-875 4050);
FORCEPROP 2 LAST $XR0 143 
J 0
(-661 4050);
DISPLAY 0.638298 (-661 4050);
PAINT MONO (-661 4050);
FORCEPROP 2 LAST $XR1 149 
J 0
(-541 4050);
DISPLAY 0.638298 (-541 4050);
PAINT MONO (-541 4050);
FORCEPROP 1 LAST COMMENT_BODY TRUE
J 0
(-925 3950);
DISPLAY 0.872340 (-925 3950);
PAINT GREEN (-925 3950);
DISPLAY INVISIBLE (-925 3950);
FORCEPROP 1 LAST OFFPAGE TRUE
J 0
(-550 3925);
DISPLAY 0.872340 (-550 3925);
PAINT GREEN (-550 3925);
DISPLAY INVISIBLE (-550 3925);
FORCEPROP 2 LAST PATH I4
J 0
(-525 4100);
DISPLAY 1.021277 (-525 4100);
PAINT ORANGE (-525 4100);
DISPLAY INVISIBLE (-525 4100);
FORCEPROP 2 LAST CDS_LIB mstr_standard
J 0
(-875 4050);
PAINT MONO (-875 4050);
DISPLAY INVISIBLE (-875 4050);
FORCEADD W_VCC_CIRCLE..1
(-3400 3325);
FORCEPROP 3 LASTPIN (-3400 3325) SIG_NAME P2V5_AUX_BMC\g
J 0
(-3390 3335);
DISPLAY 0.659574 (-3390 3335);
PAINT MONO (-3390 3335);
DISPLAY INVISIBLE (-3390 3335);
FORCEPROP 1 LAST HDL_POWER P2V5_AUX_BMC
J 1
(-3379 3400);
DISPLAY 0.872340 (-3379 3400);
PAINT ORANGE (-3379 3400);
FORCEPROP 1 LAST BODY_TYPE PLUMBING
J 0
(-3388 3319);
DISPLAY 0.340426 (-3388 3319);
PAINT GREEN (-3388 3319);
DISPLAY INVISIBLE (-3388 3319);
FORCEPROP 1 LAST PATH I40
J 0
(-3400 3325);
DISPLAY 0.617021 (-3400 3325);
PAINT GREEN (-3400 3325);
DISPLAY INVISIBLE (-3400 3325);
FORCEPROP 1 LAST CDS_LMAN_SYM_OUTLINE -100,100,100,-100
J 0
(-3400 3325);
DISPLAY 0.468085 (-3400 3325);
PAINT GREEN (-3400 3325);
DISPLAY INVISIBLE (-3400 3325);
FORCEPROP 2 LAST CDS_LIB w_power
J 0
(-3400 3325);
PAINT MONO (-3400 3325);
DISPLAY INVISIBLE (-3400 3325);
FORCEADD OFFPAGE..3
R 2
(-2975 2600);
FORCEPROP 2 LAST $XR0 143 
J 0
(-3285 2600);
DISPLAY 0.638298 (-3285 2600);
PAINT MONO (-3285 2600);
FORCEPROP 2 LAST PATH I41
J 0
(-3275 2650);
DISPLAY 1.021277 (-3275 2650);
PAINT ORANGE (-3275 2650);
DISPLAY INVISIBLE (-3275 2650);
FORCEPROP 2 LAST BOM_COST SM_CONTROLLER
J 2
(-3450 2650);
PAINT MONO (-3450 2650);
DISPLAY INVISIBLE (-3450 2650);
FORCEPROP 2 LAST ROOM BMC
J 2
(-3450 2650);
PAINT MONO (-3450 2650);
DISPLAY INVISIBLE (-3450 2650);
FORCEPROP 2 LAST CDS_LIB mstr_standard
J 0
(-2975 2600);
PAINT MONO (-2975 2600);
DISPLAY INVISIBLE (-2975 2600);
FORCEPROP 1 LAST OFFPAGE TRUE
J 2
(-3300 2475);
PAINT GREEN (-3300 2475);
DISPLAY INVISIBLE (-3300 2475);
FORCEPROP 1 LAST COMMENT_BODY TRUE
J 2
(-2925 2500);
DISPLAY 1.170213 (-2925 2500);
PAINT GREEN (-2925 2500);
DISPLAY INVISIBLE (-2925 2500);
FORCEADD OFFPAGE..3
R 2
(-2975 2500);
FORCEPROP 2 LAST $XR0 143 
J 0
(-3285 2500);
DISPLAY 0.638298 (-3285 2500);
PAINT MONO (-3285 2500);
FORCEPROP 2 LAST PATH I42
J 0
(-3275 2550);
DISPLAY 1.021277 (-3275 2550);
PAINT ORANGE (-3275 2550);
DISPLAY INVISIBLE (-3275 2550);
FORCEPROP 2 LAST BOM_COST SM_CONTROLLER
J 2
(-3450 2550);
PAINT MONO (-3450 2550);
DISPLAY INVISIBLE (-3450 2550);
FORCEPROP 2 LAST ROOM BMC
J 2
(-3450 2550);
PAINT MONO (-3450 2550);
DISPLAY INVISIBLE (-3450 2550);
FORCEPROP 2 LAST CDS_LIB mstr_standard
J 0
(-2975 2500);
PAINT MONO (-2975 2500);
DISPLAY INVISIBLE (-2975 2500);
FORCEPROP 1 LAST OFFPAGE TRUE
J 2
(-3300 2375);
PAINT GREEN (-3300 2375);
DISPLAY INVISIBLE (-3300 2375);
FORCEPROP 1 LAST COMMENT_BODY TRUE
J 2
(-2925 2400);
DISPLAY 1.170213 (-2925 2400);
PAINT GREEN (-2925 2400);
DISPLAY INVISIBLE (-2925 2400);
FORCEADD OFFPAGE..3
R 2
(-2975 2550);
FORCEPROP 2 LAST $XR0 143 
J 0
(-3285 2550);
DISPLAY 0.638298 (-3285 2550);
PAINT MONO (-3285 2550);
FORCEPROP 2 LAST PATH I43
J 0
(-3275 2600);
DISPLAY 1.021277 (-3275 2600);
PAINT ORANGE (-3275 2600);
DISPLAY INVISIBLE (-3275 2600);
FORCEPROP 2 LAST BOM_COST SM_CONTROLLER
J 2
(-3450 2600);
PAINT MONO (-3450 2600);
DISPLAY INVISIBLE (-3450 2600);
FORCEPROP 2 LAST ROOM BMC
J 2
(-3450 2600);
PAINT MONO (-3450 2600);
DISPLAY INVISIBLE (-3450 2600);
FORCEPROP 2 LAST CDS_LIB mstr_standard
J 0
(-2975 2550);
PAINT MONO (-2975 2550);
DISPLAY INVISIBLE (-2975 2550);
FORCEPROP 1 LAST OFFPAGE TRUE
J 2
(-3300 2425);
PAINT GREEN (-3300 2425);
DISPLAY INVISIBLE (-3300 2425);
FORCEPROP 1 LAST COMMENT_BODY TRUE
J 2
(-2925 2450);
DISPLAY 1.170213 (-2925 2450);
PAINT GREEN (-2925 2450);
DISPLAY INVISIBLE (-2925 2450);
FORCEADD SCD1U16V2KX-3GP..1
(-3400 3075);
FORCEPROP 1 LAST LOCATION C25W14
J 0
(-3375 3105);
DISPLAY 0.617021 (-3375 3105);
PAINT GREEN (-3375 3105);
FORCEPROP 1 LAST VALUE SCD1U16V2KX-3GP
J 0
(-3400 3000);
DISPLAY 0.617021 (-3400 3000);
PAINT GREEN (-3400 3000);
FORCEPROP 1 LAST PACK_TYPE SMD-BCG
J 0
(-3400 3075);
DISPLAY 0.617021 (-3400 3075);
PAINT GREEN (-3400 3075);
DISPLAY INVISIBLE (-3400 3075);
FORCEPROP 1 LAST PART_NUMBER 78.10421.2FL
J 0
(-3400 3075);
DISPLAY 0.617021 (-3400 3075);
PAINT GREEN (-3400 3075);
DISPLAY INVISIBLE (-3400 3075);
FORCEPROP 2 LAST CDS_LIB w_hdl
J 0
(-3400 3075);
PAINT MONO (-3400 3075);
DISPLAY INVISIBLE (-3400 3075);
FORCEPROP 1 LAST CDS_LMAN_SYM_OUTLINE -50,25,50,-25
J 0
(-3400 3075);
DISPLAY 0.468085 (-3400 3075);
PAINT GREEN (-3400 3075);
DISPLAY INVISIBLE (-3400 3075);
FORCEPROP 1 LAST PATH I44
J 0
(-3400 3075);
DISPLAY 0.617021 (-3400 3075);
PAINT GREEN (-3400 3075);
DISPLAY INVISIBLE (-3400 3075);
FORCEADD GND..1
(-3400 2825);
FORCEPROP 3 LASTPIN (-3400 2875) SIG_NAME GND\g
J 0
(-3390 2885);
DISPLAY 0.659574 (-3390 2885);
PAINT MONO (-3390 2885);
DISPLAY INVISIBLE (-3390 2885);
FORCEPROP 1 LAST HDL_POWER GND
J 0
(-3400 2975);
DISPLAY 0.872340 (-3400 2975);
PAINT GREEN (-3400 2975);
DISPLAY INVISIBLE (-3400 2975);
FORCEPROP 1 LAST BODY_TYPE PLUMBING
J 0
(-3445 2782);
DISPLAY 0.340426 (-3445 2782);
PAINT GREEN (-3445 2782);
DISPLAY INVISIBLE (-3445 2782);
FORCEPROP 1 LAST SIZE 1B
J 0
(-3325 2775);
DISPLAY 0.872340 (-3325 2775);
PAINT AQUA (-3325 2775);
DISPLAY INVISIBLE (-3325 2775);
FORCEPROP 2 LAST CDS_LIB mstr_symbols
J 0
(-3400 2825);
PAINT MONO (-3400 2825);
DISPLAY INVISIBLE (-3400 2825);
FORCEPROP 1 LAST VOLTAGE 0.0V
J 0
(-3445 2782);
DISPLAY 0.340426 (-3445 2782);
PAINT GREEN (-3445 2782);
DISPLAY INVISIBLE (-3445 2782);
FORCEPROP 1 LAST PATH I45
J 0
(-3325 2825);
DISPLAY 0.872340 (-3325 2825);
PAINT AQUA (-3325 2825);
DISPLAY INVISIBLE (-3325 2825);
FORCEADD OFFPAGE..3
R 2
(-2975 2450);
FORCEPROP 2 LAST $XR0 143 
J 0
(-3285 2450);
DISPLAY 0.638298 (-3285 2450);
PAINT MONO (-3285 2450);
FORCEPROP 2 LAST PATH I46
J 0
(-3275 2500);
DISPLAY 1.021277 (-3275 2500);
PAINT ORANGE (-3275 2500);
DISPLAY INVISIBLE (-3275 2500);
FORCEPROP 2 LAST BOM_COST SM_CONTROLLER
J 2
(-3450 2500);
PAINT MONO (-3450 2500);
DISPLAY INVISIBLE (-3450 2500);
FORCEPROP 2 LAST ROOM BMC
J 2
(-3450 2500);
PAINT MONO (-3450 2500);
DISPLAY INVISIBLE (-3450 2500);
FORCEPROP 2 LAST CDS_LIB mstr_standard
J 0
(-2975 2450);
PAINT MONO (-2975 2450);
DISPLAY INVISIBLE (-2975 2450);
FORCEPROP 1 LAST OFFPAGE TRUE
J 2
(-3300 2325);
PAINT GREEN (-3300 2325);
DISPLAY INVISIBLE (-3300 2325);
FORCEPROP 1 LAST COMMENT_BODY TRUE
J 2
(-2925 2350);
DISPLAY 1.170213 (-2925 2350);
PAINT GREEN (-2925 2350);
DISPLAY INVISIBLE (-2925 2350);
FORCEADD OFFPAGE..3
R 2
(-2975 2400);
FORCEPROP 2 LAST $XR0 143 
J 0
(-3285 2400);
DISPLAY 0.638298 (-3285 2400);
PAINT MONO (-3285 2400);
FORCEPROP 2 LAST PATH I47
J 0
(-3275 2450);
DISPLAY 1.021277 (-3275 2450);
PAINT ORANGE (-3275 2450);
DISPLAY INVISIBLE (-3275 2450);
FORCEPROP 2 LAST BOM_COST SM_CONTROLLER
J 2
(-3450 2450);
PAINT MONO (-3450 2450);
DISPLAY INVISIBLE (-3450 2450);
FORCEPROP 2 LAST ROOM BMC
J 2
(-3450 2450);
PAINT MONO (-3450 2450);
DISPLAY INVISIBLE (-3450 2450);
FORCEPROP 2 LAST CDS_LIB mstr_standard
J 0
(-2975 2400);
PAINT MONO (-2975 2400);
DISPLAY INVISIBLE (-2975 2400);
FORCEPROP 1 LAST OFFPAGE TRUE
J 2
(-3300 2275);
PAINT GREEN (-3300 2275);
DISPLAY INVISIBLE (-3300 2275);
FORCEPROP 1 LAST COMMENT_BODY TRUE
J 2
(-2925 2300);
DISPLAY 1.170213 (-2925 2300);
PAINT GREEN (-2925 2300);
DISPLAY INVISIBLE (-2925 2300);
FORCEADD OFFPAGE..3
R 2
(-2975 2350);
FORCEPROP 2 LAST $XR0 143 
J 0
(-3285 2350);
DISPLAY 0.638298 (-3285 2350);
PAINT MONO (-3285 2350);
FORCEPROP 2 LAST PATH I48
J 0
(-3275 2400);
DISPLAY 1.021277 (-3275 2400);
PAINT ORANGE (-3275 2400);
DISPLAY INVISIBLE (-3275 2400);
FORCEPROP 2 LAST BOM_COST SM_CONTROLLER
J 2
(-3450 2400);
PAINT MONO (-3450 2400);
DISPLAY INVISIBLE (-3450 2400);
FORCEPROP 2 LAST ROOM BMC
J 2
(-3450 2400);
PAINT MONO (-3450 2400);
DISPLAY INVISIBLE (-3450 2400);
FORCEPROP 2 LAST CDS_LIB mstr_standard
J 0
(-2975 2350);
PAINT MONO (-2975 2350);
DISPLAY INVISIBLE (-2975 2350);
FORCEPROP 1 LAST OFFPAGE TRUE
J 2
(-3300 2225);
PAINT GREEN (-3300 2225);
DISPLAY INVISIBLE (-3300 2225);
FORCEPROP 1 LAST COMMENT_BODY TRUE
J 2
(-2925 2250);
DISPLAY 1.170213 (-2925 2250);
PAINT GREEN (-2925 2250);
DISPLAY INVISIBLE (-2925 2250);
FORCEADD OFFPAGE..3
R 2
(-2975 2300);
FORCEPROP 2 LAST $XR0 143 
J 0
(-3285 2300);
DISPLAY 0.638298 (-3285 2300);
PAINT MONO (-3285 2300);
FORCEPROP 2 LAST PATH I49
J 0
(-3275 2350);
DISPLAY 1.021277 (-3275 2350);
PAINT ORANGE (-3275 2350);
DISPLAY INVISIBLE (-3275 2350);
FORCEPROP 2 LAST BOM_COST SM_CONTROLLER
J 2
(-3450 2350);
PAINT MONO (-3450 2350);
DISPLAY INVISIBLE (-3450 2350);
FORCEPROP 2 LAST ROOM BMC
J 2
(-3450 2350);
PAINT MONO (-3450 2350);
DISPLAY INVISIBLE (-3450 2350);
FORCEPROP 2 LAST CDS_LIB mstr_standard
J 0
(-2975 2300);
PAINT MONO (-2975 2300);
DISPLAY INVISIBLE (-2975 2300);
FORCEPROP 1 LAST OFFPAGE TRUE
J 2
(-3300 2175);
PAINT GREEN (-3300 2175);
DISPLAY INVISIBLE (-3300 2175);
FORCEPROP 1 LAST COMMENT_BODY TRUE
J 2
(-2925 2200);
DISPLAY 1.170213 (-2925 2200);
PAINT GREEN (-2925 2200);
DISPLAY INVISIBLE (-2925 2200);
FORCEADD OFFPAGE..3
(-875 3950);
FORCEPROP 2 LAST $XR0 143 
J 0
(-661 3950);
DISPLAY 0.638298 (-661 3950);
PAINT MONO (-661 3950);
FORCEPROP 2 LAST $XR1 149 
J 0
(-541 3950);
DISPLAY 0.638298 (-541 3950);
PAINT MONO (-541 3950);
FORCEPROP 1 LAST COMMENT_BODY TRUE
J 0
(-925 3850);
DISPLAY 0.872340 (-925 3850);
PAINT GREEN (-925 3850);
DISPLAY INVISIBLE (-925 3850);
FORCEPROP 1 LAST OFFPAGE TRUE
J 0
(-550 3825);
DISPLAY 0.872340 (-550 3825);
PAINT GREEN (-550 3825);
DISPLAY INVISIBLE (-550 3825);
FORCEPROP 2 LAST PATH I5
J 0
(-525 4000);
DISPLAY 1.021277 (-525 4000);
PAINT ORANGE (-525 4000);
DISPLAY INVISIBLE (-525 4000);
FORCEPROP 2 LAST CDS_LIB mstr_standard
J 0
(-875 3950);
PAINT MONO (-875 3950);
DISPLAY INVISIBLE (-875 3950);
FORCEADD OFFPAGE..3
R 2
(-2975 2250);
FORCEPROP 2 LAST $XR0 143 
J 0
(-3285 2250);
DISPLAY 0.638298 (-3285 2250);
PAINT MONO (-3285 2250);
FORCEPROP 2 LAST PATH I50
J 0
(-3275 2300);
DISPLAY 1.021277 (-3275 2300);
PAINT ORANGE (-3275 2300);
DISPLAY INVISIBLE (-3275 2300);
FORCEPROP 2 LAST BOM_COST SM_CONTROLLER
J 2
(-3450 2300);
PAINT MONO (-3450 2300);
DISPLAY INVISIBLE (-3450 2300);
FORCEPROP 2 LAST ROOM BMC
J 2
(-3450 2300);
PAINT MONO (-3450 2300);
DISPLAY INVISIBLE (-3450 2300);
FORCEPROP 2 LAST CDS_LIB mstr_standard
J 0
(-2975 2250);
PAINT MONO (-2975 2250);
DISPLAY INVISIBLE (-2975 2250);
FORCEPROP 1 LAST OFFPAGE TRUE
J 2
(-3300 2125);
PAINT GREEN (-3300 2125);
DISPLAY INVISIBLE (-3300 2125);
FORCEPROP 1 LAST COMMENT_BODY TRUE
J 2
(-2925 2150);
DISPLAY 1.170213 (-2925 2150);
PAINT GREEN (-2925 2150);
DISPLAY INVISIBLE (-2925 2150);
FORCEADD OFFPAGE..3
R 2
(-2975 2150);
FORCEPROP 2 LAST $XR0 143 
J 0
(-3285 2150);
DISPLAY 0.638298 (-3285 2150);
PAINT MONO (-3285 2150);
FORCEPROP 2 LAST PATH I51
J 0
(-3275 2200);
DISPLAY 1.021277 (-3275 2200);
PAINT ORANGE (-3275 2200);
DISPLAY INVISIBLE (-3275 2200);
FORCEPROP 2 LAST BOM_COST SM_CONTROLLER
J 2
(-3450 2200);
PAINT MONO (-3450 2200);
DISPLAY INVISIBLE (-3450 2200);
FORCEPROP 2 LAST ROOM BMC
J 2
(-3450 2200);
PAINT MONO (-3450 2200);
DISPLAY INVISIBLE (-3450 2200);
FORCEPROP 2 LAST CDS_LIB mstr_standard
J 0
(-2975 2150);
PAINT MONO (-2975 2150);
DISPLAY INVISIBLE (-2975 2150);
FORCEPROP 1 LAST OFFPAGE TRUE
J 2
(-3300 2025);
PAINT GREEN (-3300 2025);
DISPLAY INVISIBLE (-3300 2025);
FORCEPROP 1 LAST COMMENT_BODY TRUE
J 2
(-2925 2050);
DISPLAY 1.170213 (-2925 2050);
PAINT GREEN (-2925 2050);
DISPLAY INVISIBLE (-2925 2050);
FORCEADD OFFPAGE..3
R 2
(-2975 2100);
FORCEPROP 2 LAST $XR0 143 
J 0
(-3285 2100);
DISPLAY 0.638298 (-3285 2100);
PAINT MONO (-3285 2100);
FORCEPROP 2 LAST PATH I52
J 0
(-3275 2150);
DISPLAY 1.021277 (-3275 2150);
PAINT ORANGE (-3275 2150);
DISPLAY INVISIBLE (-3275 2150);
FORCEPROP 2 LAST BOM_COST SM_CONTROLLER
J 2
(-3450 2150);
PAINT MONO (-3450 2150);
DISPLAY INVISIBLE (-3450 2150);
FORCEPROP 2 LAST ROOM BMC
J 2
(-3450 2150);
PAINT MONO (-3450 2150);
DISPLAY INVISIBLE (-3450 2150);
FORCEPROP 2 LAST CDS_LIB mstr_standard
J 0
(-2975 2100);
PAINT MONO (-2975 2100);
DISPLAY INVISIBLE (-2975 2100);
FORCEPROP 1 LAST OFFPAGE TRUE
J 2
(-3300 1975);
PAINT GREEN (-3300 1975);
DISPLAY INVISIBLE (-3300 1975);
FORCEPROP 1 LAST COMMENT_BODY TRUE
J 2
(-2925 2000);
DISPLAY 1.170213 (-2925 2000);
PAINT GREEN (-2925 2000);
DISPLAY INVISIBLE (-2925 2000);
FORCEADD OFFPAGE..3
R 2
(-2975 2000);
FORCEPROP 2 LAST $XR0 143 
J 0
(-3285 2000);
DISPLAY 0.638298 (-3285 2000);
PAINT MONO (-3285 2000);
FORCEPROP 2 LAST PATH I53
J 0
(-3275 2050);
DISPLAY 1.021277 (-3275 2050);
PAINT ORANGE (-3275 2050);
DISPLAY INVISIBLE (-3275 2050);
FORCEPROP 2 LAST BOM_COST SM_CONTROLLER
J 2
(-3450 2050);
PAINT MONO (-3450 2050);
DISPLAY INVISIBLE (-3450 2050);
FORCEPROP 2 LAST ROOM BMC
J 2
(-3450 2050);
PAINT MONO (-3450 2050);
DISPLAY INVISIBLE (-3450 2050);
FORCEPROP 2 LAST CDS_LIB mstr_standard
J 0
(-2975 2000);
PAINT MONO (-2975 2000);
DISPLAY INVISIBLE (-2975 2000);
FORCEPROP 1 LAST OFFPAGE TRUE
J 2
(-3300 1875);
PAINT GREEN (-3300 1875);
DISPLAY INVISIBLE (-3300 1875);
FORCEPROP 1 LAST COMMENT_BODY TRUE
J 2
(-2925 1900);
DISPLAY 1.170213 (-2925 1900);
PAINT GREEN (-2925 1900);
DISPLAY INVISIBLE (-2925 1900);
FORCEADD OFFPAGE..3
R 2
(-2975 2050);
FORCEPROP 2 LAST $XR0 143 
J 0
(-3285 2050);
DISPLAY 0.638298 (-3285 2050);
PAINT MONO (-3285 2050);
FORCEPROP 2 LAST PATH I54
J 0
(-3275 2100);
DISPLAY 1.021277 (-3275 2100);
PAINT ORANGE (-3275 2100);
DISPLAY INVISIBLE (-3275 2100);
FORCEPROP 2 LAST BOM_COST SM_CONTROLLER
J 2
(-3450 2100);
PAINT MONO (-3450 2100);
DISPLAY INVISIBLE (-3450 2100);
FORCEPROP 2 LAST ROOM BMC
J 2
(-3450 2100);
PAINT MONO (-3450 2100);
DISPLAY INVISIBLE (-3450 2100);
FORCEPROP 2 LAST CDS_LIB mstr_standard
J 0
(-2975 2050);
PAINT MONO (-2975 2050);
DISPLAY INVISIBLE (-2975 2050);
FORCEPROP 1 LAST OFFPAGE TRUE
J 2
(-3300 1925);
PAINT GREEN (-3300 1925);
DISPLAY INVISIBLE (-3300 1925);
FORCEPROP 1 LAST COMMENT_BODY TRUE
J 2
(-2925 1950);
DISPLAY 1.170213 (-2925 1950);
PAINT GREEN (-2925 1950);
DISPLAY INVISIBLE (-2925 1950);
FORCEADD RES..2
(-3550 2425);
FORCEPROP 1 LAST PACK_TYPE 0402
J 0
(-3510 2250);
DISPLAY 0.617021 (-3510 2250);
PAINT SKYBLUE (-3510 2250);
FORCEPROP 1 LAST MATERIAL CHIP
J 0
(-3510 2350);
DISPLAY 0.617021 (-3510 2350);
PAINT SKYBLUE (-3510 2350);
FORCEPROP 1 LAST LOCATION R25W117
J 0
(-3505 2575);
DISPLAY 0.617021 (-3505 2575);
PAINT AQUA (-3505 2575);
FORCEPROP 1 LAST TOLERANCE 1.0%
J 0
(-3505 2450);
DISPLAY 0.617021 (-3505 2450);
PAINT SKYBLUE (-3505 2450);
FORCEPROP 1 LAST VALUE 240
J 0
(-3505 2500);
DISPLAY 0.617021 (-3505 2500);
PAINT SKYBLUE (-3505 2500);
FORCEPROP 1 LASTPIN (-3550 2525) $PN 1
J 0
(-3545 2487);
DISPLAY 0.787234 (-3545 2487);
PAINT ORANGE (-3545 2487);
DISPLAY INVISIBLE (-3545 2487);
FORCEPROP 1 LASTPIN (-3550 2325) $PN 2
J 0
(-3545 2335);
DISPLAY 0.787234 (-3545 2335);
PAINT ORANGE (-3545 2335);
DISPLAY INVISIBLE (-3545 2335);
FORCEPROP 1 LAST PATH I55
J 0
(-3500 2600);
DISPLAY 0.978723 (-3500 2600);
PAINT WHITE (-3500 2600);
DISPLAY INVISIBLE (-3500 2600);
FORCEPROP 2 LAST BOM_COST SM_MEM
J 0
(-3500 2650);
DISPLAY 1.021277 (-3500 2650);
PAINT ORANGE (-3500 2650);
DISPLAY INVISIBLE (-3500 2650);
FORCEPROP 2 LAST ROOM BMC_MEMORY
J 0
(-3500 2600);
DISPLAY 1.021277 (-3500 2600);
PAINT ORANGE (-3500 2600);
DISPLAY INVISIBLE (-3500 2600);
FORCEPROP 2 LAST CDS_LIB mstr_discrete
R 3
J 0
(-3550 2425);
PAINT MONO (-3550 2425);
DISPLAY INVISIBLE (-3550 2425);
FORCEPROP 1 LAST WATTAGE 1/16W
J 0
(-3510 2400);
DISPLAY 0.617021 (-3510 2400);
PAINT SKYBLUE (-3510 2400);
DISPLAY INVISIBLE (-3510 2400);
FORCEPROP 1 LAST PART_NUMBER G21796-294
J 0
(-3510 2300);
DISPLAY 0.617021 (-3510 2300);
PAINT BLUE (-3510 2300);
DISPLAY INVISIBLE (-3510 2300);
FORCEADD GND..1
(-3550 2050);
FORCEPROP 3 LASTPIN (-3550 2100) SIG_NAME GND\g
J 0
(-3540 2110);
DISPLAY 0.659574 (-3540 2110);
PAINT MONO (-3540 2110);
DISPLAY INVISIBLE (-3540 2110);
FORCEPROP 1 LAST PATH I56
J 0
(-3475 2050);
DISPLAY 0.872340 (-3475 2050);
PAINT AQUA (-3475 2050);
DISPLAY INVISIBLE (-3475 2050);
FORCEPROP 1 LAST SIZE 1B
J 0
(-3475 2000);
DISPLAY 0.872340 (-3475 2000);
PAINT AQUA (-3475 2000);
DISPLAY INVISIBLE (-3475 2000);
FORCEPROP 2 LAST CDS_LIB mstr_symbols
J 0
(-3550 2050);
PAINT MONO (-3550 2050);
DISPLAY INVISIBLE (-3550 2050);
FORCEPROP 1 LAST VOLTAGE 0.0V
J 0
(-3595 2007);
DISPLAY 0.340426 (-3595 2007);
PAINT GREEN (-3595 2007);
DISPLAY INVISIBLE (-3595 2007);
FORCEPROP 1 LAST BODY_TYPE PLUMBING
J 0
(-3595 2007);
DISPLAY 0.340426 (-3595 2007);
PAINT GREEN (-3595 2007);
DISPLAY INVISIBLE (-3595 2007);
FORCEPROP 1 LAST HDL_POWER GND
J 0
(-3550 2200);
DISPLAY 0.872340 (-3550 2200);
PAINT GREEN (-3550 2200);
DISPLAY INVISIBLE (-3550 2200);
FORCEADD OFFPAGE..3
R 2
(-2975 1950);
FORCEPROP 2 LAST $XR0 143 
J 0
(-3285 1950);
DISPLAY 0.638298 (-3285 1950);
PAINT MONO (-3285 1950);
FORCEPROP 2 LAST PATH I57
J 0
(-3275 2000);
DISPLAY 1.021277 (-3275 2000);
PAINT ORANGE (-3275 2000);
DISPLAY INVISIBLE (-3275 2000);
FORCEPROP 2 LAST BOM_COST SM_CONTROLLER
J 2
(-3450 2000);
PAINT MONO (-3450 2000);
DISPLAY INVISIBLE (-3450 2000);
FORCEPROP 2 LAST ROOM BMC
J 2
(-3450 2000);
PAINT MONO (-3450 2000);
DISPLAY INVISIBLE (-3450 2000);
FORCEPROP 2 LAST CDS_LIB mstr_standard
J 0
(-2975 1950);
PAINT MONO (-2975 1950);
DISPLAY INVISIBLE (-2975 1950);
FORCEPROP 1 LAST OFFPAGE TRUE
J 2
(-3300 1825);
PAINT GREEN (-3300 1825);
DISPLAY INVISIBLE (-3300 1825);
FORCEPROP 1 LAST COMMENT_BODY TRUE
J 2
(-2925 1850);
DISPLAY 1.170213 (-2925 1850);
PAINT GREEN (-2925 1850);
DISPLAY INVISIBLE (-2925 1850);
FORCEADD OFFPAGE..3
R 2
(-2975 1900);
FORCEPROP 2 LAST $XR0 143 
J 0
(-3285 1900);
DISPLAY 0.638298 (-3285 1900);
PAINT MONO (-3285 1900);
FORCEPROP 2 LAST PATH I58
J 0
(-3275 1950);
DISPLAY 1.021277 (-3275 1950);
PAINT ORANGE (-3275 1950);
DISPLAY INVISIBLE (-3275 1950);
FORCEPROP 2 LAST BOM_COST SM_CONTROLLER
J 2
(-3450 1950);
PAINT MONO (-3450 1950);
DISPLAY INVISIBLE (-3450 1950);
FORCEPROP 2 LAST ROOM BMC
J 2
(-3450 1950);
PAINT MONO (-3450 1950);
DISPLAY INVISIBLE (-3450 1950);
FORCEPROP 2 LAST CDS_LIB mstr_standard
J 0
(-2975 1900);
PAINT MONO (-2975 1900);
DISPLAY INVISIBLE (-2975 1900);
FORCEPROP 1 LAST OFFPAGE TRUE
J 2
(-3300 1775);
PAINT GREEN (-3300 1775);
DISPLAY INVISIBLE (-3300 1775);
FORCEPROP 1 LAST COMMENT_BODY TRUE
J 2
(-2925 1800);
DISPLAY 1.170213 (-2925 1800);
PAINT GREEN (-2925 1800);
DISPLAY INVISIBLE (-2925 1800);
FORCEADD OFFPAGE..3
R 2
(-2975 1850);
FORCEPROP 2 LAST $XR0 143 
J 0
(-3285 1850);
DISPLAY 0.638298 (-3285 1850);
PAINT MONO (-3285 1850);
FORCEPROP 2 LAST PATH I59
J 0
(-3275 1900);
DISPLAY 1.021277 (-3275 1900);
PAINT ORANGE (-3275 1900);
DISPLAY INVISIBLE (-3275 1900);
FORCEPROP 2 LAST BOM_COST SM_CONTROLLER
J 2
(-3450 1900);
PAINT MONO (-3450 1900);
DISPLAY INVISIBLE (-3450 1900);
FORCEPROP 2 LAST ROOM BMC
J 2
(-3450 1900);
PAINT MONO (-3450 1900);
DISPLAY INVISIBLE (-3450 1900);
FORCEPROP 2 LAST CDS_LIB mstr_standard
J 0
(-2975 1850);
PAINT MONO (-2975 1850);
DISPLAY INVISIBLE (-2975 1850);
FORCEPROP 1 LAST OFFPAGE TRUE
J 2
(-3300 1725);
PAINT GREEN (-3300 1725);
DISPLAY INVISIBLE (-3300 1725);
FORCEPROP 1 LAST COMMENT_BODY TRUE
J 2
(-2925 1750);
DISPLAY 1.170213 (-2925 1750);
PAINT GREEN (-2925 1750);
DISPLAY INVISIBLE (-2925 1750);
FORCEADD OFFPAGE..3
(-875 3900);
FORCEPROP 2 LAST $XR1 149 
J 0
(-541 3900);
DISPLAY 0.638298 (-541 3900);
PAINT MONO (-541 3900);
FORCEPROP 2 LAST $XR0 143 
J 0
(-661 3900);
DISPLAY 0.638298 (-661 3900);
PAINT MONO (-661 3900);
FORCEPROP 1 LAST COMMENT_BODY TRUE
J 0
(-925 3800);
DISPLAY 0.872340 (-925 3800);
PAINT GREEN (-925 3800);
DISPLAY INVISIBLE (-925 3800);
FORCEPROP 1 LAST OFFPAGE TRUE
J 0
(-550 3775);
DISPLAY 0.872340 (-550 3775);
PAINT GREEN (-550 3775);
DISPLAY INVISIBLE (-550 3775);
FORCEPROP 2 LAST PATH I6
J 0
(-525 3950);
DISPLAY 1.021277 (-525 3950);
PAINT ORANGE (-525 3950);
DISPLAY INVISIBLE (-525 3950);
FORCEPROP 2 LAST CDS_LIB mstr_standard
J 0
(-875 3900);
PAINT MONO (-875 3900);
DISPLAY INVISIBLE (-875 3900);
FORCEADD OFFPAGE..3
R 2
(-2975 1800);
FORCEPROP 2 LAST $XR0 143 
J 0
(-3285 1800);
DISPLAY 0.638298 (-3285 1800);
PAINT MONO (-3285 1800);
FORCEPROP 2 LAST PATH I60
J 0
(-3275 1850);
DISPLAY 1.021277 (-3275 1850);
PAINT ORANGE (-3275 1850);
DISPLAY INVISIBLE (-3275 1850);
FORCEPROP 2 LAST BOM_COST SM_CONTROLLER
J 2
(-3450 1850);
PAINT MONO (-3450 1850);
DISPLAY INVISIBLE (-3450 1850);
FORCEPROP 2 LAST ROOM BMC
J 2
(-3450 1850);
PAINT MONO (-3450 1850);
DISPLAY INVISIBLE (-3450 1850);
FORCEPROP 2 LAST CDS_LIB mstr_standard
J 0
(-2975 1800);
PAINT MONO (-2975 1800);
DISPLAY INVISIBLE (-2975 1800);
FORCEPROP 1 LAST OFFPAGE TRUE
J 2
(-3300 1675);
PAINT GREEN (-3300 1675);
DISPLAY INVISIBLE (-3300 1675);
FORCEPROP 1 LAST COMMENT_BODY TRUE
J 2
(-2925 1700);
DISPLAY 1.170213 (-2925 1700);
PAINT GREEN (-2925 1700);
DISPLAY INVISIBLE (-2925 1700);
FORCEADD OFFPAGE..3
R 2
(-2975 1700);
FORCEPROP 2 LAST $XR0 143 
J 0
(-3285 1700);
DISPLAY 0.638298 (-3285 1700);
PAINT MONO (-3285 1700);
FORCEPROP 2 LAST PATH I61
J 0
(-3275 1750);
DISPLAY 1.021277 (-3275 1750);
PAINT ORANGE (-3275 1750);
DISPLAY INVISIBLE (-3275 1750);
FORCEPROP 2 LAST BOM_COST SM_CONTROLLER
J 2
(-3450 1750);
PAINT MONO (-3450 1750);
DISPLAY INVISIBLE (-3450 1750);
FORCEPROP 2 LAST ROOM BMC
J 2
(-3450 1750);
PAINT MONO (-3450 1750);
DISPLAY INVISIBLE (-3450 1750);
FORCEPROP 2 LAST CDS_LIB mstr_standard
J 0
(-2975 1700);
PAINT MONO (-2975 1700);
DISPLAY INVISIBLE (-2975 1700);
FORCEPROP 1 LAST OFFPAGE TRUE
J 2
(-3300 1575);
PAINT GREEN (-3300 1575);
DISPLAY INVISIBLE (-3300 1575);
FORCEPROP 1 LAST COMMENT_BODY TRUE
J 2
(-2925 1600);
DISPLAY 1.170213 (-2925 1600);
PAINT GREEN (-2925 1600);
DISPLAY INVISIBLE (-2925 1600);
FORCEADD OFFPAGE..3
R 2
(-2975 1650);
FORCEPROP 2 LAST $XR0 143 
J 0
(-3285 1650);
DISPLAY 0.638298 (-3285 1650);
PAINT MONO (-3285 1650);
FORCEPROP 2 LAST PATH I62
J 0
(-3275 1700);
DISPLAY 1.021277 (-3275 1700);
PAINT ORANGE (-3275 1700);
DISPLAY INVISIBLE (-3275 1700);
FORCEPROP 2 LAST BOM_COST SM_CONTROLLER
J 2
(-3450 1700);
PAINT MONO (-3450 1700);
DISPLAY INVISIBLE (-3450 1700);
FORCEPROP 2 LAST ROOM BMC
J 2
(-3450 1700);
PAINT MONO (-3450 1700);
DISPLAY INVISIBLE (-3450 1700);
FORCEPROP 2 LAST CDS_LIB mstr_standard
J 0
(-2975 1650);
PAINT MONO (-2975 1650);
DISPLAY INVISIBLE (-2975 1650);
FORCEPROP 1 LAST OFFPAGE TRUE
J 2
(-3300 1525);
PAINT GREEN (-3300 1525);
DISPLAY INVISIBLE (-3300 1525);
FORCEPROP 1 LAST COMMENT_BODY TRUE
J 2
(-2925 1550);
DISPLAY 1.170213 (-2925 1550);
PAINT GREEN (-2925 1550);
DISPLAY INVISIBLE (-2925 1550);
FORCEADD OFFPAGE..3
R 2
(-2975 1600);
FORCEPROP 2 LAST $XR0 143 
J 0
(-3285 1600);
DISPLAY 0.638298 (-3285 1600);
PAINT MONO (-3285 1600);
FORCEPROP 2 LAST PATH I63
J 0
(-3275 1650);
DISPLAY 1.021277 (-3275 1650);
PAINT ORANGE (-3275 1650);
DISPLAY INVISIBLE (-3275 1650);
FORCEPROP 2 LAST BOM_COST SM_CONTROLLER
J 2
(-3450 1650);
PAINT MONO (-3450 1650);
DISPLAY INVISIBLE (-3450 1650);
FORCEPROP 2 LAST ROOM BMC
J 2
(-3450 1650);
PAINT MONO (-3450 1650);
DISPLAY INVISIBLE (-3450 1650);
FORCEPROP 2 LAST CDS_LIB mstr_standard
J 0
(-2975 1600);
PAINT MONO (-2975 1600);
DISPLAY INVISIBLE (-2975 1600);
FORCEPROP 1 LAST OFFPAGE TRUE
J 2
(-3300 1475);
PAINT GREEN (-3300 1475);
DISPLAY INVISIBLE (-3300 1475);
FORCEPROP 1 LAST COMMENT_BODY TRUE
J 2
(-2925 1500);
DISPLAY 1.170213 (-2925 1500);
PAINT GREEN (-2925 1500);
DISPLAY INVISIBLE (-2925 1500);
FORCEADD OFFPAGE..3
R 2
(-2975 1550);
FORCEPROP 2 LAST $XR0 143 
J 0
(-3285 1550);
DISPLAY 0.638298 (-3285 1550);
PAINT MONO (-3285 1550);
FORCEPROP 2 LAST PATH I64
J 0
(-3275 1600);
DISPLAY 1.021277 (-3275 1600);
PAINT ORANGE (-3275 1600);
DISPLAY INVISIBLE (-3275 1600);
FORCEPROP 2 LAST BOM_COST SM_CONTROLLER
J 2
(-3450 1600);
PAINT MONO (-3450 1600);
DISPLAY INVISIBLE (-3450 1600);
FORCEPROP 2 LAST ROOM BMC
J 2
(-3450 1600);
PAINT MONO (-3450 1600);
DISPLAY INVISIBLE (-3450 1600);
FORCEPROP 2 LAST CDS_LIB mstr_standard
J 0
(-2975 1550);
PAINT MONO (-2975 1550);
DISPLAY INVISIBLE (-2975 1550);
FORCEPROP 1 LAST OFFPAGE TRUE
J 2
(-3300 1425);
PAINT GREEN (-3300 1425);
DISPLAY INVISIBLE (-3300 1425);
FORCEPROP 1 LAST COMMENT_BODY TRUE
J 2
(-2925 1450);
DISPLAY 1.170213 (-2925 1450);
PAINT GREEN (-2925 1450);
DISPLAY INVISIBLE (-2925 1450);
FORCEADD CAP..1
(-3800 2475);
FORCEPROP 1 LAST PACK_TYPE 0402LF
J 0
(-3750 2275);
DISPLAY 0.617021 (-3750 2275);
PAINT SKYBLUE (-3750 2275);
FORCEPROP 1 LAST VOLTAGE 16V
J 0
(-3775 2525);
DISPLAY 0.617021 (-3775 2525);
PAINT SKYBLUE (-3775 2525);
FORCEPROP 1 LAST VALUE 0.1UF
J 0
(-3775 2575);
DISPLAY 0.617021 (-3775 2575);
PAINT SKYBLUE (-3775 2575);
FORCEPROP 1 LAST LOCATION C25W13
J 0
(-3775 2625);
DISPLAY 0.617021 (-3775 2625);
PAINT AQUA (-3775 2625);
FORCEPROP 1 LAST TOLERANCE 10%
J 0
(-3750 2425);
DISPLAY 0.617021 (-3750 2425);
PAINT SKYBLUE (-3750 2425);
DISPLAY INVISIBLE (-3750 2425);
FORCEPROP 1 LAST MATERIAL X7R
J 0
(-3750 2375);
DISPLAY 0.617021 (-3750 2375);
PAINT SKYBLUE (-3750 2375);
DISPLAY INVISIBLE (-3750 2375);
FORCEPROP 1 LAST PART_NUMBER A36096-030
J 0
(-3750 2325);
DISPLAY 0.617021 (-3750 2325);
PAINT BLUE (-3750 2325);
DISPLAY INVISIBLE (-3750 2325);
FORCEPROP 2 LAST CDS_LIB mstr_discrete
R 3
J 0
(-3800 2475);
PAINT MONO (-3800 2475);
DISPLAY INVISIBLE (-3800 2475);
FORCEPROP 0 LAST ROOM BMC
J 0
(-3750 2675);
DISPLAY 1.021277 (-3750 2675);
PAINT ORANGE (-3750 2675);
DISPLAY INVISIBLE (-3750 2675);
FORCEPROP 0 LAST BOM_COST SM_CONTROLLER
J 0
(-3750 2675);
DISPLAY 1.021277 (-3750 2675);
PAINT ORANGE (-3750 2675);
DISPLAY INVISIBLE (-3750 2675);
FORCEPROP 1 LAST PATH I65
J 0
(-3750 2625);
DISPLAY 0.978723 (-3750 2625);
PAINT WHITE (-3750 2625);
DISPLAY INVISIBLE (-3750 2625);
FORCEPROP 1 LASTPIN (-3800 2375) $PN 2
J 0
(-3790 2355);
DISPLAY 0.787234 (-3790 2355);
PAINT ORANGE (-3790 2355);
DISPLAY INVISIBLE (-3790 2355);
FORCEPROP 1 LASTPIN (-3800 2575) $PN 1
J 0
(-3790 2555);
DISPLAY 0.787234 (-3790 2555);
PAINT ORANGE (-3790 2555);
DISPLAY INVISIBLE (-3790 2555);
FORCEADD GND..1
(-3800 2050);
FORCEPROP 3 LASTPIN (-3800 2100) SIG_NAME GND\g
J 0
(-3790 2110);
DISPLAY 0.659574 (-3790 2110);
PAINT MONO (-3790 2110);
DISPLAY INVISIBLE (-3790 2110);
FORCEPROP 1 LAST HDL_POWER GND
J 0
(-3800 2200);
DISPLAY 0.872340 (-3800 2200);
PAINT GREEN (-3800 2200);
DISPLAY INVISIBLE (-3800 2200);
FORCEPROP 1 LAST BODY_TYPE PLUMBING
J 0
(-3845 2007);
DISPLAY 0.340426 (-3845 2007);
PAINT GREEN (-3845 2007);
DISPLAY INVISIBLE (-3845 2007);
FORCEPROP 1 LAST SIZE 1B
J 0
(-3725 2000);
DISPLAY 0.872340 (-3725 2000);
PAINT AQUA (-3725 2000);
DISPLAY INVISIBLE (-3725 2000);
FORCEPROP 2 LAST CDS_LIB mstr_symbols
J 0
(-3800 2050);
PAINT MONO (-3800 2050);
DISPLAY INVISIBLE (-3800 2050);
FORCEPROP 1 LAST VOLTAGE 0.0V
J 0
(-3845 2007);
DISPLAY 0.340426 (-3845 2007);
PAINT GREEN (-3845 2007);
DISPLAY INVISIBLE (-3845 2007);
FORCEPROP 1 LAST PATH I66
J 0
(-3725 2050);
DISPLAY 0.872340 (-3725 2050);
PAINT AQUA (-3725 2050);
DISPLAY INVISIBLE (-3725 2050);
FORCEADD W_VCC_CIRCLE..1
(-4950 4900);
FORCEPROP 3 LASTPIN (-4950 4900) SIG_NAME P1V2_AUX_BMC\g
J 0
(-4940 4910);
DISPLAY 0.659574 (-4940 4910);
PAINT MONO (-4940 4910);
DISPLAY INVISIBLE (-4940 4910);
FORCEPROP 1 LAST HDL_POWER P1V2_AUX_BMC
J 1
(-4929 4975);
DISPLAY 0.872340 (-4929 4975);
PAINT ORANGE (-4929 4975);
FORCEPROP 1 LAST BODY_TYPE PLUMBING
J 0
(-4938 4894);
DISPLAY 0.340426 (-4938 4894);
PAINT GREEN (-4938 4894);
DISPLAY INVISIBLE (-4938 4894);
FORCEPROP 1 LAST CDS_LMAN_SYM_OUTLINE -100,100,100,-100
J 0
(-4950 4900);
DISPLAY 0.468085 (-4950 4900);
PAINT GREEN (-4950 4900);
DISPLAY INVISIBLE (-4950 4900);
FORCEPROP 2 LAST CDS_LIB w_power
J 0
(-4950 4900);
PAINT MONO (-4950 4900);
DISPLAY INVISIBLE (-4950 4900);
FORCEPROP 1 LAST PATH I67
J 0
(-4950 4900);
DISPLAY 0.617021 (-4950 4900);
PAINT GREEN (-4950 4900);
DISPLAY INVISIBLE (-4950 4900);
FORCEADD SC1U16V3KX-2GP..1
(-4775 4700);
FORCEPROP 1 LAST VALUE SC1U16V3KX-2GP
J 0
(-4750 4650);
DISPLAY 0.617021 (-4750 4650);
PAINT GREEN (-4750 4650);
FORCEPROP 1 LAST LOCATION C25W18
J 0
(-4750 4730);
DISPLAY 0.617021 (-4750 4730);
PAINT GREEN (-4750 4730);
FORCEPROP 1 LAST PACK_TYPE SMD-BCG
J 0
(-4775 4700);
DISPLAY 0.617021 (-4775 4700);
PAINT GREEN (-4775 4700);
DISPLAY INVISIBLE (-4775 4700);
FORCEPROP 1 LAST PART_NUMBER 78.10521.5BL
J 0
(-4775 4700);
DISPLAY 0.617021 (-4775 4700);
PAINT GREEN (-4775 4700);
DISPLAY INVISIBLE (-4775 4700);
FORCEPROP 2 LAST CDS_LIB w_hdl
J 0
(-4775 4700);
PAINT MONO (-4775 4700);
DISPLAY INVISIBLE (-4775 4700);
FORCEPROP 1 LAST CDS_LMAN_SYM_OUTLINE -50,25,50,-25
J 0
(-4775 4700);
DISPLAY 0.468085 (-4775 4700);
PAINT GREEN (-4775 4700);
DISPLAY INVISIBLE (-4775 4700);
FORCEPROP 1 LAST PATH I68
J 0
(-4775 4700);
DISPLAY 0.617021 (-4775 4700);
PAINT GREEN (-4775 4700);
DISPLAY INVISIBLE (-4775 4700);
FORCEADD SC4D7U10V3KX-GP..1
(-4950 4700);
FORCEPROP 1 LAST LOCATION C25W19
J 0
(-4925 4730);
DISPLAY 0.617021 (-4925 4730);
PAINT GREEN (-4925 4730);
FORCEPROP 1 LAST VALUE SC4D7U10V3KX-GP
J 0
(-5275 4650);
DISPLAY 0.617021 (-5275 4650);
PAINT GREEN (-5275 4650);
FORCEPROP 2 LAST CDS_LIB w_hdl
J 0
(-4950 4700);
PAINT MONO (-4950 4700);
DISPLAY INVISIBLE (-4950 4700);
FORCEPROP 1 LAST CDS_LMAN_SYM_OUTLINE -50,25,50,-25
J 0
(-4950 4700);
DISPLAY 0.468085 (-4950 4700);
PAINT GREEN (-4950 4700);
DISPLAY INVISIBLE (-4950 4700);
FORCEPROP 1 LAST PACK_TYPE SMD-BCG
J 0
(-4950 4700);
DISPLAY 0.617021 (-4950 4700);
PAINT GREEN (-4950 4700);
DISPLAY INVISIBLE (-4950 4700);
FORCEPROP 1 LAST PART_NUMBER 78.47523.5BL
J 0
(-4950 4700);
DISPLAY 0.617021 (-4950 4700);
PAINT GREEN (-4950 4700);
DISPLAY INVISIBLE (-4950 4700);
FORCEPROP 1 LAST PATH I69
J 0
(-4950 4700);
DISPLAY 0.617021 (-4950 4700);
PAINT GREEN (-4950 4700);
DISPLAY INVISIBLE (-4950 4700);
FORCEADD OFFPAGE..3
(-875 3800);
FORCEPROP 2 LAST $XR1 149 
J 0
(-541 3800);
DISPLAY 0.638298 (-541 3800);
PAINT MONO (-541 3800);
FORCEPROP 2 LAST $XR0 143 
J 0
(-661 3800);
DISPLAY 0.638298 (-661 3800);
PAINT MONO (-661 3800);
FORCEPROP 1 LAST COMMENT_BODY TRUE
J 0
(-925 3700);
DISPLAY 0.872340 (-925 3700);
PAINT GREEN (-925 3700);
DISPLAY INVISIBLE (-925 3700);
FORCEPROP 1 LAST OFFPAGE TRUE
J 0
(-550 3675);
DISPLAY 0.872340 (-550 3675);
PAINT GREEN (-550 3675);
DISPLAY INVISIBLE (-550 3675);
FORCEPROP 2 LAST CDS_LIB mstr_standard
J 0
(-875 3800);
PAINT MONO (-875 3800);
DISPLAY INVISIBLE (-875 3800);
FORCEPROP 2 LAST PATH I7
J 0
(-525 3850);
DISPLAY 1.021277 (-525 3850);
PAINT ORANGE (-525 3850);
DISPLAY INVISIBLE (-525 3850);
FORCEADD GND..1
(-4950 4425);
FORCEPROP 3 LASTPIN (-4950 4475) SIG_NAME GND\g
J 0
(-4940 4485);
DISPLAY 0.659574 (-4940 4485);
PAINT MONO (-4940 4485);
DISPLAY INVISIBLE (-4940 4485);
FORCEPROP 1 LAST HDL_POWER GND
J 0
(-4950 4575);
DISPLAY 0.872340 (-4950 4575);
PAINT GREEN (-4950 4575);
DISPLAY INVISIBLE (-4950 4575);
FORCEPROP 1 LAST BODY_TYPE PLUMBING
J 0
(-4995 4382);
DISPLAY 0.340426 (-4995 4382);
PAINT GREEN (-4995 4382);
DISPLAY INVISIBLE (-4995 4382);
FORCEPROP 2 LAST CDS_LIB mstr_symbols
J 0
(-4950 4425);
PAINT MONO (-4950 4425);
DISPLAY INVISIBLE (-4950 4425);
FORCEPROP 1 LAST SIZE 1B
J 0
(-4875 4375);
DISPLAY 0.872340 (-4875 4375);
PAINT AQUA (-4875 4375);
DISPLAY INVISIBLE (-4875 4375);
FORCEPROP 1 LAST VOLTAGE 0.0V
J 0
(-4995 4382);
DISPLAY 0.340426 (-4995 4382);
PAINT GREEN (-4995 4382);
DISPLAY INVISIBLE (-4995 4382);
FORCEPROP 1 LAST PATH I70
J 0
(-4875 4425);
DISPLAY 0.872340 (-4875 4425);
PAINT AQUA (-4875 4425);
DISPLAY INVISIBLE (-4875 4425);
FORCEADD CAP..1
R 1
(-5300 4300);
FORCEPROP 1 LAST TOLERANCE 10%
R 1
J 0
(-5250 4350);
DISPLAY 0.617021 (-5250 4350);
PAINT SKYBLUE (-5250 4350);
FORCEPROP 1 LAST VOLTAGE 16V
R 1
J 0
(-5300 4350);
DISPLAY 0.617021 (-5300 4350);
PAINT SKYBLUE (-5300 4350);
FORCEPROP 1 LAST PACK_TYPE 0402
R 1
J 0
(-5100 4350);
DISPLAY 0.617021 (-5100 4350);
PAINT SKYBLUE (-5100 4350);
FORCEPROP 1 LAST MATERIAL X6S
R 1
J 0
(-5200 4350);
DISPLAY 0.617021 (-5200 4350);
PAINT SKYBLUE (-5200 4350);
FORCEPROP 1 LAST PART_NUMBER D97712-011
R 1
J 0
(-5150 4350);
DISPLAY 0.617021 (-5150 4350);
PAINT BLUE (-5150 4350);
FORCEPROP 1 LAST VALUE 1.0UF
R 1
J 0
(-5350 4350);
DISPLAY 0.617021 (-5350 4350);
PAINT SKYBLUE (-5350 4350);
FORCEPROP 1 LAST LOCATION C25W1
R 1
J 0
(-5400 4350);
DISPLAY 0.617021 (-5400 4350);
PAINT AQUA (-5400 4350);
FORCEPROP 2 LAST CDS_LIB mstr_discrete
R 1
J 0
(-5300 4300);
PAINT MONO (-5300 4300);
DISPLAY INVISIBLE (-5300 4300);
FORCEPROP 2 LAST ROOM VDDQ_KLM_PWR_VR
R 1
J 0
(-5450 4350);
DISPLAY 1.361702 (-5450 4350);
PAINT ORANGE (-5450 4350);
DISPLAY INVISIBLE (-5450 4350);
FORCEPROP 1 LAST PATH I71
R 1
J 0
(-5450 4350);
DISPLAY 0.978723 (-5450 4350);
PAINT WHITE (-5450 4350);
DISPLAY INVISIBLE (-5450 4350);
FORCEPROP 1 LASTPIN (-5200 4300) $PN 2
R 1
J 0
(-5180 4310);
DISPLAY 0.787234 (-5180 4310);
PAINT ORANGE (-5180 4310);
DISPLAY INVISIBLE (-5180 4310);
FORCEPROP 1 LASTPIN (-5400 4300) $PN 1
R 1
J 0
(-5380 4310);
DISPLAY 0.787234 (-5380 4310);
PAINT ORANGE (-5380 4310);
DISPLAY INVISIBLE (-5380 4310);
FORCEADD CAP..1
R 1
(-5300 4050);
FORCEPROP 1 LAST PART_NUMBER D97712-011
R 1
J 0
(-5150 4100);
DISPLAY 0.617021 (-5150 4100);
PAINT BLUE (-5150 4100);
FORCEPROP 1 LAST VOLTAGE 16V
R 1
J 0
(-5300 4100);
DISPLAY 0.617021 (-5300 4100);
PAINT SKYBLUE (-5300 4100);
FORCEPROP 1 LAST PACK_TYPE 0402
R 1
J 0
(-5100 4100);
DISPLAY 0.617021 (-5100 4100);
PAINT SKYBLUE (-5100 4100);
FORCEPROP 1 LAST VALUE 1.0UF
R 1
J 0
(-5350 4100);
DISPLAY 0.617021 (-5350 4100);
PAINT SKYBLUE (-5350 4100);
FORCEPROP 1 LAST LOCATION C25W2
R 1
J 0
(-5400 4100);
DISPLAY 0.617021 (-5400 4100);
PAINT AQUA (-5400 4100);
FORCEPROP 1 LAST TOLERANCE 10%
R 1
J 0
(-5250 4100);
DISPLAY 0.617021 (-5250 4100);
PAINT SKYBLUE (-5250 4100);
FORCEPROP 1 LAST MATERIAL X6S
R 1
J 0
(-5200 4100);
DISPLAY 0.617021 (-5200 4100);
PAINT SKYBLUE (-5200 4100);
FORCEPROP 2 LAST CDS_LIB mstr_discrete
J 0
(-5300 4050);
PAINT MONO (-5300 4050);
DISPLAY INVISIBLE (-5300 4050);
FORCEPROP 2 LAST ROOM VDDQ_KLM_PWR_VR
R 1
J 0
(-5450 4100);
DISPLAY 1.361702 (-5450 4100);
PAINT ORANGE (-5450 4100);
DISPLAY INVISIBLE (-5450 4100);
FORCEPROP 1 LAST PATH I72
R 1
J 0
(-5450 4100);
DISPLAY 0.978723 (-5450 4100);
PAINT WHITE (-5450 4100);
DISPLAY INVISIBLE (-5450 4100);
FORCEPROP 1 LASTPIN (-5200 4050) $PN 2
R 1
J 0
(-5180 4060);
DISPLAY 0.787234 (-5180 4060);
PAINT ORANGE (-5180 4060);
DISPLAY INVISIBLE (-5180 4060);
FORCEPROP 1 LASTPIN (-5400 4050) $PN 1
R 1
J 0
(-5380 4060);
DISPLAY 0.787234 (-5380 4060);
PAINT ORANGE (-5380 4060);
DISPLAY INVISIBLE (-5380 4060);
FORCEADD CAP..1
R 1
(-5300 3800);
FORCEPROP 1 LAST PACK_TYPE 0402
R 1
J 0
(-5100 3850);
DISPLAY 0.617021 (-5100 3850);
PAINT SKYBLUE (-5100 3850);
FORCEPROP 1 LAST MATERIAL X6S
R 1
J 0
(-5200 3850);
DISPLAY 0.617021 (-5200 3850);
PAINT SKYBLUE (-5200 3850);
FORCEPROP 1 LAST LOCATION C25W3
R 1
J 0
(-5400 3850);
DISPLAY 0.617021 (-5400 3850);
PAINT AQUA (-5400 3850);
FORCEPROP 1 LAST TOLERANCE 10%
R 1
J 0
(-5250 3850);
DISPLAY 0.617021 (-5250 3850);
PAINT SKYBLUE (-5250 3850);
FORCEPROP 1 LAST VALUE 1.0UF
R 1
J 0
(-5350 3850);
DISPLAY 0.617021 (-5350 3850);
PAINT SKYBLUE (-5350 3850);
FORCEPROP 1 LAST VOLTAGE 16V
R 1
J 0
(-5300 3850);
DISPLAY 0.617021 (-5300 3850);
PAINT SKYBLUE (-5300 3850);
FORCEPROP 1 LAST PART_NUMBER D97712-011
R 1
J 0
(-5150 3850);
DISPLAY 0.617021 (-5150 3850);
PAINT BLUE (-5150 3850);
FORCEPROP 2 LAST ROOM VDDQ_KLM_PWR_VR
R 1
J 0
(-5450 3850);
DISPLAY 1.361702 (-5450 3850);
PAINT ORANGE (-5450 3850);
DISPLAY INVISIBLE (-5450 3850);
FORCEPROP 2 LAST CDS_LIB mstr_discrete
J 0
(-5300 3800);
PAINT MONO (-5300 3800);
DISPLAY INVISIBLE (-5300 3800);
FORCEPROP 1 LAST PATH I73
R 1
J 0
(-5450 3850);
DISPLAY 0.978723 (-5450 3850);
PAINT WHITE (-5450 3850);
DISPLAY INVISIBLE (-5450 3850);
FORCEPROP 1 LASTPIN (-5200 3800) $PN 2
R 1
J 0
(-5180 3810);
DISPLAY 0.787234 (-5180 3810);
PAINT ORANGE (-5180 3810);
DISPLAY INVISIBLE (-5180 3810);
FORCEPROP 1 LASTPIN (-5400 3800) $PN 1
R 1
J 0
(-5380 3810);
DISPLAY 0.787234 (-5380 3810);
PAINT ORANGE (-5380 3810);
DISPLAY INVISIBLE (-5380 3810);
FORCEADD CAP..1
R 1
(-5300 3550);
FORCEPROP 1 LAST VOLTAGE 16V
R 1
J 0
(-5300 3600);
DISPLAY 0.617021 (-5300 3600);
PAINT SKYBLUE (-5300 3600);
FORCEPROP 1 LAST TOLERANCE 10%
R 1
J 0
(-5250 3600);
DISPLAY 0.617021 (-5250 3600);
PAINT SKYBLUE (-5250 3600);
FORCEPROP 1 LAST PART_NUMBER D97712-011
R 1
J 0
(-5150 3600);
DISPLAY 0.617021 (-5150 3600);
PAINT BLUE (-5150 3600);
FORCEPROP 1 LAST PACK_TYPE 0402
R 1
J 0
(-5100 3600);
DISPLAY 0.617021 (-5100 3600);
PAINT SKYBLUE (-5100 3600);
FORCEPROP 1 LAST MATERIAL X6S
R 1
J 0
(-5200 3600);
DISPLAY 0.617021 (-5200 3600);
PAINT SKYBLUE (-5200 3600);
FORCEPROP 1 LAST VALUE 1.0UF
R 1
J 0
(-5350 3600);
DISPLAY 0.617021 (-5350 3600);
PAINT SKYBLUE (-5350 3600);
FORCEPROP 1 LAST LOCATION C25W4
R 1
J 0
(-5400 3600);
DISPLAY 0.617021 (-5400 3600);
PAINT AQUA (-5400 3600);
FORCEPROP 2 LAST ROOM VDDQ_KLM_PWR_VR
R 1
J 0
(-5450 3600);
DISPLAY 1.361702 (-5450 3600);
PAINT ORANGE (-5450 3600);
DISPLAY INVISIBLE (-5450 3600);
FORCEPROP 2 LAST CDS_LIB mstr_discrete
J 0
(-5300 3550);
PAINT MONO (-5300 3550);
DISPLAY INVISIBLE (-5300 3550);
FORCEPROP 1 LAST PATH I74
R 1
J 0
(-5450 3600);
DISPLAY 0.978723 (-5450 3600);
PAINT WHITE (-5450 3600);
DISPLAY INVISIBLE (-5450 3600);
FORCEPROP 1 LASTPIN (-5200 3550) $PN 2
R 1
J 0
(-5180 3560);
DISPLAY 0.787234 (-5180 3560);
PAINT ORANGE (-5180 3560);
DISPLAY INVISIBLE (-5180 3560);
FORCEPROP 1 LASTPIN (-5400 3550) $PN 1
R 1
J 0
(-5380 3560);
DISPLAY 0.787234 (-5380 3560);
PAINT ORANGE (-5380 3560);
DISPLAY INVISIBLE (-5380 3560);
FORCEADD W_VCC_CIRCLE..1
(-5575 4525);
FORCEPROP 3 LASTPIN (-5575 4525) SIG_NAME P1V2_AUX_BMC\g
J 0
(-5565 4535);
DISPLAY 0.659574 (-5565 4535);
PAINT MONO (-5565 4535);
DISPLAY INVISIBLE (-5565 4535);
FORCEPROP 1 LAST HDL_POWER P1V2_AUX_BMC
J 1
(-5554 4600);
DISPLAY 0.872340 (-5554 4600);
PAINT ORANGE (-5554 4600);
FORCEPROP 1 LAST BODY_TYPE PLUMBING
J 0
(-5563 4519);
DISPLAY 0.340426 (-5563 4519);
PAINT GREEN (-5563 4519);
DISPLAY INVISIBLE (-5563 4519);
FORCEPROP 1 LAST CDS_LMAN_SYM_OUTLINE -100,100,100,-100
J 0
(-5575 4525);
DISPLAY 0.468085 (-5575 4525);
PAINT GREEN (-5575 4525);
DISPLAY INVISIBLE (-5575 4525);
FORCEPROP 2 LAST CDS_LIB w_power
J 0
(-5575 4525);
PAINT MONO (-5575 4525);
DISPLAY INVISIBLE (-5575 4525);
FORCEPROP 1 LAST PATH I75
J 0
(-5575 4525);
DISPLAY 0.617021 (-5575 4525);
PAINT GREEN (-5575 4525);
DISPLAY INVISIBLE (-5575 4525);
FORCEADD OFFPAGE..3
(-875 3850);
FORCEPROP 2 LAST $XR1 149 
J 0
(-541 3850);
DISPLAY 0.638298 (-541 3850);
PAINT MONO (-541 3850);
FORCEPROP 2 LAST $XR0 143 
J 0
(-661 3850);
DISPLAY 0.638298 (-661 3850);
PAINT MONO (-661 3850);
FORCEPROP 1 LAST COMMENT_BODY TRUE
J 0
(-925 3750);
DISPLAY 0.872340 (-925 3750);
PAINT GREEN (-925 3750);
DISPLAY INVISIBLE (-925 3750);
FORCEPROP 1 LAST OFFPAGE TRUE
J 0
(-550 3725);
DISPLAY 0.872340 (-550 3725);
PAINT GREEN (-550 3725);
DISPLAY INVISIBLE (-550 3725);
FORCEPROP 2 LAST CDS_LIB mstr_standard
J 0
(-875 3850);
PAINT MONO (-875 3850);
DISPLAY INVISIBLE (-875 3850);
FORCEPROP 2 LAST PATH I8
J 0
(-525 3900);
DISPLAY 1.021277 (-525 3900);
PAINT ORANGE (-525 3900);
DISPLAY INVISIBLE (-525 3900);
FORCEADD OFFPAGE..3
(-875 3750);
FORCEPROP 2 LAST $XR0 143 
J 0
(-661 3750);
DISPLAY 0.638298 (-661 3750);
PAINT MONO (-661 3750);
FORCEPROP 2 LAST $XR1 149 
J 0
(-541 3750);
DISPLAY 0.638298 (-541 3750);
PAINT MONO (-541 3750);
FORCEPROP 1 LAST COMMENT_BODY TRUE
J 0
(-925 3650);
DISPLAY 0.872340 (-925 3650);
PAINT GREEN (-925 3650);
DISPLAY INVISIBLE (-925 3650);
FORCEPROP 1 LAST OFFPAGE TRUE
J 0
(-550 3625);
DISPLAY 0.872340 (-550 3625);
PAINT GREEN (-550 3625);
DISPLAY INVISIBLE (-550 3625);
FORCEPROP 2 LAST CDS_LIB mstr_standard
J 0
(-875 3750);
PAINT MONO (-875 3750);
DISPLAY INVISIBLE (-875 3750);
FORCEPROP 2 LAST PATH I9
J 0
(-525 3800);
DISPLAY 1.021277 (-525 3800);
PAINT ORANGE (-525 3800);
DISPLAY INVISIBLE (-525 3800);
FORCEADD P3V3_STBY..1
(-4550 2825);
FORCEPROP 3 LASTPIN (-4550 2775) SIG_NAME P3V3_STBY\g
J 0
(-4540 2785);
DISPLAY 0.659574 (-4540 2785);
PAINT MONO (-4540 2785);
DISPLAY INVISIBLE (-4540 2785);
FORCEPROP 1 LAST HDL_POWER P3V3_STBY
J 0
(-4850 2700);
DISPLAY 0.872340 (-4850 2700);
PAINT ORANGE (-4850 2700);
DISPLAY INVISIBLE (-4850 2700);
FORCEPROP 1 LAST BODY_TYPE PLUMBING
J 0
(-4595 2782);
DISPLAY 0.340426 (-4595 2782);
PAINT GREEN (-4595 2782);
DISPLAY INVISIBLE (-4595 2782);
FORCEPROP 1 LAST VOLTAGE 3.3V
J 0
(-4595 2782);
DISPLAY 0.340426 (-4595 2782);
PAINT SKYBLUE (-4595 2782);
DISPLAY INVISIBLE (-4595 2782);
FORCEPROP 2 LAST CDS_LIB mstr_symbols
J 0
(-4550 2825);
PAINT ORANGE (-4550 2825);
DISPLAY INVISIBLE (-4550 2825);
FORCEPROP 1 LAST SIZE 1B
J 0
(-4505 2847);
DISPLAY 0.340426 (-4505 2847);
PAINT GREEN (-4505 2847);
DISPLAY INVISIBLE (-4505 2847);
FORCEPROP 1 LAST PATH I93
J 0
(-4505 2827);
DISPLAY 0.340426 (-4505 2827);
PAINT GREEN (-4505 2827);
DISPLAY INVISIBLE (-4505 2827);
FORCEADD RES..1
(-4800 2625);
FORCEPROP 1 LAST PART_NUMBER G21796-271
J 0
(-4850 2725);
DISPLAY 0.617021 (-4850 2725);
PAINT BLUE (-4850 2725);
FORCEPROP 1 LAST PACK_TYPE 0402
J 0
(-4550 2475);
DISPLAY 0.617021 (-4550 2475);
PAINT SKYBLUE (-4550 2475);
FORCEPROP 1 LAST WATTAGE 1/16W
J 2
(-4825 2475);
DISPLAY 0.617021 (-4825 2475);
PAINT SKYBLUE (-4825 2475);
FORCEPROP 1 LAST MATERIAL CHIP
J 0
(-4800 2475);
DISPLAY 0.617021 (-4800 2475);
PAINT SKYBLUE (-4800 2475);
FORCEPROP 1 LAST VALUE 221
J 2
(-4825 2525);
DISPLAY 0.617021 (-4825 2525);
PAINT SKYBLUE (-4825 2525);
FORCEPROP 1 LASTPIN (-4700 2625) $PN 2
J 0
(-4738 2637);
DISPLAY 0.617021 (-4738 2637);
PAINT ORANGE (-4738 2637);
FORCEPROP 1 LASTPIN (-4900 2625) $PN 1
J 0
(-4888 2637);
DISPLAY 0.617021 (-4888 2637);
PAINT ORANGE (-4888 2637);
FORCEPROP 1 LAST LOCATION R9E24
J 0
(-4850 2675);
DISPLAY 0.617021 (-4850 2675);
PAINT AQUA (-4850 2675);
FORCEPROP 1 LAST TOLERANCE 1.0%
J 0
(-4800 2525);
DISPLAY 0.617021 (-4800 2525);
PAINT SKYBLUE (-4800 2525);
FORCEPROP 0 LAST CDS_SEC 1
J 0
(-4850 2775);
PAINT MONO (-4850 2775);
DISPLAY INVISIBLE (-4850 2775);
FORCEPROP 0 LAST CDS_LOCATION R9E24
J 0
(-4850 2775);
PAINT MONO (-4850 2775);
DISPLAY INVISIBLE (-4850 2775);
FORCEPROP 2 LAST CDS_LIB mstr_discrete
J 0
(-4800 2625);
PAINT ORANGE (-4800 2625);
DISPLAY INVISIBLE (-4800 2625);
FORCEPROP 2 LAST ROOM BMC
J 0
(-4850 2775);
DISPLAY 1.021277 (-4850 2775);
PAINT ORANGE (-4850 2775);
DISPLAY INVISIBLE (-4850 2775);
FORCEPROP 2 LAST SEC_TYPE 0402
J 0
(-4850 2825);
DISPLAY 1.021277 (-4850 2825);
PAINT ORANGE (-4850 2825);
DISPLAY INVISIBLE (-4850 2825);
FORCEPROP 2 LAST BOM_COST SM_CONTROLLER
J 0
(-4850 2825);
DISPLAY 1.021277 (-4850 2825);
PAINT ORANGE (-4850 2825);
DISPLAY INVISIBLE (-4850 2825);
FORCEPROP 2 LAST SEC 1
J 0
(-4850 2825);
DISPLAY 0.680851 (-4850 2825);
PAINT MONO (-4850 2825);
DISPLAY INVISIBLE (-4850 2825);
FORCEPROP 1 LAST PATH I94
J 0
(-4850 2775);
DISPLAY 0.978723 (-4850 2775);
PAINT WHITE (-4850 2775);
DISPLAY INVISIBLE (-4850 2775);
FORCEADD GND..1
(-5000 2925);
FORCEPROP 3 LASTPIN (-5000 2975) SIG_NAME GND\g
J 0
(-4990 2985);
DISPLAY 0.659574 (-4990 2985);
PAINT MONO (-4990 2985);
DISPLAY INVISIBLE (-4990 2985);
FORCEPROP 1 LAST HDL_POWER GND
J 0
(-5000 3075);
DISPLAY 0.872340 (-5000 3075);
PAINT GREEN (-5000 3075);
DISPLAY INVISIBLE (-5000 3075);
FORCEPROP 1 LAST BODY_TYPE PLUMBING
J 0
(-5045 2882);
DISPLAY 0.340426 (-5045 2882);
PAINT GREEN (-5045 2882);
DISPLAY INVISIBLE (-5045 2882);
FORCEPROP 1 LAST VOLTAGE 0.0V
J 0
(-5045 2882);
DISPLAY 0.340426 (-5045 2882);
PAINT GREEN (-5045 2882);
DISPLAY INVISIBLE (-5045 2882);
FORCEPROP 1 LAST SIZE 1B
J 0
(-4925 2875);
DISPLAY 0.872340 (-4925 2875);
PAINT AQUA (-4925 2875);
DISPLAY INVISIBLE (-4925 2875);
FORCEPROP 2 LAST CDS_LIB mstr_symbols
J 0
(-5000 2925);
PAINT MONO (-5000 2925);
DISPLAY INVISIBLE (-5000 2925);
FORCEPROP 1 LAST PATH I95
J 0
(-4925 2925);
DISPLAY 0.872340 (-4925 2925);
PAINT AQUA (-4925 2925);
DISPLAY INVISIBLE (-4925 2925);
FORCEADD CAP..1
R 1
(-5300 3300);
FORCEPROP 1 LAST VALUE 1.0UF
R 1
J 0
(-5350 3350);
DISPLAY 0.617021 (-5350 3350);
PAINT SKYBLUE (-5350 3350);
FORCEPROP 1 LAST LOCATION C25W5
R 1
J 0
(-5400 3350);
DISPLAY 0.617021 (-5400 3350);
PAINT AQUA (-5400 3350);
FORCEPROP 1 LAST TOLERANCE 10%
R 1
J 0
(-5250 3350);
DISPLAY 0.617021 (-5250 3350);
PAINT SKYBLUE (-5250 3350);
FORCEPROP 1 LAST VOLTAGE 16V
R 1
J 0
(-5300 3350);
DISPLAY 0.617021 (-5300 3350);
PAINT SKYBLUE (-5300 3350);
FORCEPROP 1 LAST PACK_TYPE 0402
R 1
J 0
(-5100 3350);
DISPLAY 0.617021 (-5100 3350);
PAINT SKYBLUE (-5100 3350);
FORCEPROP 1 LAST PART_NUMBER D97712-011
R 1
J 0
(-5150 3350);
DISPLAY 0.617021 (-5150 3350);
PAINT BLUE (-5150 3350);
FORCEPROP 1 LAST MATERIAL X6S
R 1
J 0
(-5200 3350);
DISPLAY 0.617021 (-5200 3350);
PAINT SKYBLUE (-5200 3350);
FORCEPROP 2 LAST ROOM VDDQ_KLM_PWR_VR
R 1
J 0
(-5450 3350);
DISPLAY 1.361702 (-5450 3350);
PAINT ORANGE (-5450 3350);
DISPLAY INVISIBLE (-5450 3350);
FORCEPROP 2 LAST CDS_LIB mstr_discrete
J 0
(-5300 3300);
PAINT MONO (-5300 3300);
DISPLAY INVISIBLE (-5300 3300);
FORCEPROP 1 LAST PATH I96
R 1
J 0
(-5450 3350);
DISPLAY 0.978723 (-5450 3350);
PAINT WHITE (-5450 3350);
DISPLAY INVISIBLE (-5450 3350);
FORCEPROP 1 LASTPIN (-5200 3300) $PN 2
R 1
J 0
(-5180 3310);
DISPLAY 0.787234 (-5180 3310);
PAINT ORANGE (-5180 3310);
DISPLAY INVISIBLE (-5180 3310);
FORCEPROP 1 LASTPIN (-5400 3300) $PN 1
R 1
J 0
(-5380 3310);
DISPLAY 0.787234 (-5380 3310);
PAINT ORANGE (-5380 3310);
DISPLAY INVISIBLE (-5380 3310);
FORCEADD CAP..1
R 1
(-5300 3050);
FORCEPROP 1 LAST LOCATION C25W6
R 1
J 0
(-5400 3100);
DISPLAY 0.617021 (-5400 3100);
PAINT AQUA (-5400 3100);
FORCEPROP 1 LAST VALUE 1.0UF
R 1
J 0
(-5350 3100);
DISPLAY 0.617021 (-5350 3100);
PAINT SKYBLUE (-5350 3100);
FORCEPROP 1 LAST MATERIAL X6S
R 1
J 0
(-5200 3100);
DISPLAY 0.617021 (-5200 3100);
PAINT SKYBLUE (-5200 3100);
FORCEPROP 1 LAST VOLTAGE 16V
R 1
J 0
(-5300 3100);
DISPLAY 0.617021 (-5300 3100);
PAINT SKYBLUE (-5300 3100);
FORCEPROP 1 LAST TOLERANCE 10%
R 1
J 0
(-5250 3100);
DISPLAY 0.617021 (-5250 3100);
PAINT SKYBLUE (-5250 3100);
FORCEPROP 1 LAST PACK_TYPE 0402
R 1
J 0
(-5100 3100);
DISPLAY 0.617021 (-5100 3100);
PAINT SKYBLUE (-5100 3100);
FORCEPROP 1 LAST PART_NUMBER D97712-011
R 1
J 0
(-5150 3100);
DISPLAY 0.617021 (-5150 3100);
PAINT BLUE (-5150 3100);
FORCEPROP 2 LAST ROOM VDDQ_KLM_PWR_VR
R 1
J 0
(-5450 3100);
DISPLAY 1.361702 (-5450 3100);
PAINT ORANGE (-5450 3100);
DISPLAY INVISIBLE (-5450 3100);
FORCEPROP 2 LAST CDS_LIB mstr_discrete
J 0
(-5300 3050);
PAINT MONO (-5300 3050);
DISPLAY INVISIBLE (-5300 3050);
FORCEPROP 1 LAST PATH I97
R 1
J 0
(-5450 3100);
DISPLAY 0.978723 (-5450 3100);
PAINT WHITE (-5450 3100);
DISPLAY INVISIBLE (-5450 3100);
FORCEPROP 1 LASTPIN (-5200 3050) $PN 2
R 1
J 0
(-5180 3060);
DISPLAY 0.787234 (-5180 3060);
PAINT ORANGE (-5180 3060);
DISPLAY INVISIBLE (-5180 3060);
FORCEPROP 1 LASTPIN (-5400 3050) $PN 1
R 1
J 0
(-5380 3060);
DISPLAY 0.787234 (-5380 3060);
PAINT ORANGE (-5380 3060);
DISPLAY INVISIBLE (-5380 3060);
FORCEADD LED..3
(-5400 2625);
FORCEPROP 2 LASTPIN (-5300 2625) $PN 1
J 0
(-5290 2560);
DISPLAY 0.617021 (-5290 2560);
PAINT ORANGE (-5290 2560);
FORCEPROP 2 LASTPIN (-5500 2625) $PN 2
J 2
(-5510 2560);
DISPLAY 0.617021 (-5510 2560);
PAINT ORANGE (-5510 2560);
FORCEPROP 1 LAST PART_NUMBER C97278-010
J 0
(-5500 2475);
DISPLAY 0.617021 (-5500 2475);
PAINT BLUE (-5500 2475);
FORCEPROP 1 LAST COLOR GREEN
J 0
(-5500 2725);
DISPLAY 0.617021 (-5500 2725);
PAINT BLUE (-5500 2725);
FORCEPROP 1 LAST MATERIAL IC
J 0
(-5500 2775);
DISPLAY 0.617021 (-5500 2775);
PAINT SKYBLUE (-5500 2775);
FORCEPROP 1 LAST LOCATION DS9E1
J 0
(-5500 2825);
DISPLAY 0.617021 (-5500 2825);
PAINT AQUA (-5500 2825);
FORCEPROP 0 LAST CDS_SEC 1
J 0
(-5500 2875);
PAINT MONO (-5500 2875);
DISPLAY INVISIBLE (-5500 2875);
FORCEPROP 2 LAST CDS_LIB mstr_discrete
J 0
(-5400 2625);
PAINT ORANGE (-5400 2625);
DISPLAY INVISIBLE (-5400 2625);
FORCEPROP 2 LAST SEC 1
J 0
(-5500 2875);
DISPLAY 0.680851 (-5500 2875);
PAINT MONO (-5500 2875);
DISPLAY INVISIBLE (-5500 2875);
FORCEPROP 2 LAST CDS_LOCATION DS9E1
J 0
(-5500 2825);
DISPLAY 0.617021 (-5500 2825);
PAINT AQUA (-5500 2825);
DISPLAY INVISIBLE (-5500 2825);
FORCEPROP 2 LAST ROOM BMC
J 0
(-5500 2875);
DISPLAY 1.021277 (-5500 2875);
PAINT ORANGE (-5500 2875);
DISPLAY INVISIBLE (-5500 2875);
FORCEPROP 1 LAST PACK_TYPE A1LF
J 0
(-5500 2875);
DISPLAY 0.978723 (-5500 2875);
PAINT SKYBLUE (-5500 2875);
DISPLAY INVISIBLE (-5500 2875);
FORCEPROP 2 LAST SEC_TYPE A1LF
J 0
(-5500 2875);
DISPLAY 1.021277 (-5500 2875);
PAINT ORANGE (-5500 2875);
DISPLAY INVISIBLE (-5500 2875);
FORCEPROP 2 LAST BOM_COST SM_CONTROLLER
J 0
(-5500 2925);
DISPLAY 1.021277 (-5500 2925);
PAINT ORANGE (-5500 2925);
DISPLAY INVISIBLE (-5500 2925);
FORCEPROP 1 LAST PATH I98
J 0
(-5050 2775);
DISPLAY 0.978723 (-5050 2775);
PAINT BLUE (-5050 2775);
DISPLAY INVISIBLE (-5050 2775);
FORCEADD CAD_NOTE..1
(-5550 1625);
FORCEPROP 0 LAST L1 PLEASE PLACE LED NEAR BMC
J 0
(-5725 1500);
DISPLAY 1.021277 (-5725 1500);
PAINT ORANGE (-5725 1500);
FORCEPROP 1 LAST COMMENT_BODY TRUE
J 0
(-5525 1725);
DISPLAY 0.978723 (-5525 1725);
PAINT ORANGE (-5525 1725);
DISPLAY INVISIBLE (-5525 1725);
FORCEPROP 2 LAST CDS_LIB mstr_symbols
J 0
(-5550 1625);
PAINT MONO (-5550 1625);
DISPLAY INVISIBLE (-5550 1625);
FORCEADD DNS..2
(-4670 745);
PAINT RED (-4670 745);
FORCEPROP 1 LAST COMMENT_BODY TRUE
R 1
J 0
(-4595 520);
DISPLAY 0.872340 (-4595 520);
PAINT GREEN (-4595 520);
DISPLAY INVISIBLE (-4595 520);
FORCEPROP 2 LAST CDS_LIB mstr_misc
J 0
(-4670 745);
PAINT MONO (-4670 745);
DISPLAY INVISIBLE (-4670 745);
FORCEADD INTEL_CORP_BPAGE..1
(0 75);
FORCEPROP 1 LAST CDS_CON_LAST_MODIFIED Tue Dec 01 11:52:06 2015
J 0
(-1425 400);
DISPLAY 1.361702 (-1425 400);
PAINT GREEN (-1425 400);
DISPLAY INVISIBLE (-1425 400);
FORCEPROP 1 LAST CUSTOM_TXT_CDS <CURRENT_DESIGN_SHEET> OF <TOTAL_DESIGN_SHEETS>
J 0
(-500 100);
PAINT GREEN (-500 100);
FORCEPROP 1 LAST CUSTOM_TXT_CDS <CON_LAST_MODIFIED>
J 0
(-1925 425);
PAINT GREEN (-1925 425);
FORCEPROP 2 LAST CUSTOM_TXT_CDS <XR_PAGE_TITLE>
J 0
(-7890 5325);
DISPLAY 0.638298 (-7890 5325);
PAINT PINK (-7890 5325);
DISPLAY INVISIBLE (-7890 5325);
FORCEPROP 1 LAST SCH_TITLE BMC DDR4 MEMORY
J 0
(-7950 125);
DISPLAY 1.212766 (-7950 125);
PAINT ORANGE (-7950 125);
FORCEPROP 1 LAST SCH_NUMBER H4694802
J 0
(-1300 225);
DISPLAY 1.212766 (-1300 225);
PAINT YELLOW (-1300 225);
FORCEPROP 1 LAST SCH_REV 2.420
J 0
(-250 225);
DISPLAY 0.978723 (-250 225);
PAINT YELLOW (-250 225);
FORCEPROP 1 LAST SCH_ADDRESS3 Santa Clara, CA 95052-8119
J 0
(-3975 100);
DISPLAY 0.617021 (-3975 100);
PAINT GREEN (-3975 100);
FORCEPROP 1 LAST SCH_ADDRESS2 P.O. BOX 58119
J 0
(-3975 150);
DISPLAY 0.617021 (-3975 150);
PAINT GREEN (-3975 150);
FORCEPROP 1 LAST SCH_DEPT BESD
J 1
(-4450 175);
DISPLAY 1.212766 (-4450 175);
PAINT YELLOW (-4450 175);
FORCEPROP 1 LAST SCH_ADDRESS1 2200 Mission College Blvd.
J 0
(-3975 200);
DISPLAY 0.617021 (-3975 200);
PAINT GREEN (-3975 200);
FORCEPROP 1 LAST COMMENT_BODY TRUE
J 0
(12 87);
DISPLAY 0.617021 (12 87);
PAINT GREEN (12 87);
DISPLAY INVISIBLE (12 87);
FORCEPROP 2 LAST CDS_LIB mstr_symbols
J 0
(0 75);
PAINT MONO (0 75);
DISPLAY INVISIBLE (0 75);
FORCEPROP 2 LAST PAGE_BORDER TRUE
J 0
(-7890 5325);
DISPLAY 0.851064 (-7890 5325);
PAINT PINK (-7890 5325);
DISPLAY INVISIBLE (-7890 5325);
FORCEPROP 2 LAST CDS_XR_PAGE_TITLE CR-149 : @BASEBOARD_FAB2_LIB.BASEBOARD_FAB2(SCH_1):PAGE149
J 0
(-7890 5325);
DISPLAY 0.638298 (-7890 5325);
PAINT PINK (-7890 5325);
DISPLAY INVISIBLE (-7890 5325);
WIRE 16 -1 (-6200 2425)(-6200 2500);
WIRE 16 -1 (-5600 1975)(-5600 2050);
WIRE 16 -1 (-6200 1575)(-6200 1625);
WIRE 16 -1 (-4675 1200)(-4675 1300);
WIRE 16 -1 (-4675 475)(-4675 650);
WIRE 16 -1 (-6775 1125)(-6775 1225);
WIRE 16 -1 (-6775 1225)(-6175 1225);
WIRE 16 -1 (-6175 1150)(-6175 1225);
WIRE 16 -1 (-6175 1225)(-6175 1375);
WIRE 16 -1 (-6775 325)(-6450 325);
WIRE 16 -1 (-6775 325)(-6775 525);
WIRE 16 -1 (-6450 325)(-6450 525);
WIRE 16 -1 (-6450 325)(-6175 325);
WIRE 16 -1 (-6175 325)(-6175 525);
WIRE 16 -1 (-6175 225)(-6175 325);
WIRE 16 -1 (-1725 4875)(-1725 4925);
WIRE 16 -1 (-7650 4300)(-7900 4300);
WIRE 16 -1 (-7900 4300)(-7900 4250);
WIRE 16 -1 (-7650 4250)(-7900 4250);
WIRE 16 -1 (-7900 4200)(-7900 4250);
WIRE 16 -1 (-7650 4200)(-7900 4200);
WIRE 16 -1 (-7900 4150)(-7900 4200);
WIRE 16 -1 (-7650 4150)(-7900 4150);
WIRE 16 -1 (-7900 4100)(-7900 4150);
WIRE 16 -1 (-7650 4100)(-7900 4100);
WIRE 16 -1 (-7900 4050)(-7900 4100);
WIRE 16 -1 (-7650 4050)(-7900 4050);
WIRE 16 -1 (-7900 4000)(-7900 4050);
WIRE 16 -1 (-7650 4000)(-7900 4000);
WIRE 16 -1 (-7900 3950)(-7900 4000);
WIRE 16 -1 (-7650 3950)(-7900 3950);
WIRE 16 -1 (-7900 3900)(-7900 3950);
WIRE 16 -1 (-7650 3900)(-7900 3900);
WIRE 16 -1 (-7900 3850)(-7900 3900);
WIRE 16 -1 (-7650 3850)(-7900 3850);
WIRE 16 -1 (-7900 3800)(-7900 3850);
WIRE 16 -1 (-7650 3800)(-7900 3800);
WIRE 16 -1 (-7900 3750)(-7900 3800);
WIRE 16 -1 (-7650 3750)(-7900 3750);
WIRE 16 -1 (-7900 3700)(-7900 3750);
WIRE 16 -1 (-7650 3700)(-7900 3700);
WIRE 16 -1 (-7900 3650)(-7900 3700);
WIRE 16 -1 (-7650 3650)(-7900 3650);
WIRE 16 -1 (-7900 3600)(-7900 3650);
WIRE 16 -1 (-7650 3600)(-7900 3600);
WIRE 16 -1 (-7900 3550)(-7900 3600);
WIRE 16 -1 (-7650 3550)(-7900 3550);
WIRE 16 -1 (-7900 3500)(-7900 3550);
WIRE 16 -1 (-7650 3500)(-7900 3500);
WIRE 16 -1 (-7900 3450)(-7900 3500);
WIRE 16 -1 (-7650 3450)(-7900 3450);
WIRE 16 -1 (-7900 3400)(-7900 3450);
WIRE 16 -1 (-7650 3400)(-7900 3400);
WIRE 16 -1 (-7900 3350)(-7900 3400);
WIRE 16 -1 (-7650 3350)(-7900 3350);
WIRE 16 -1 (-7900 3300)(-7900 3350);
WIRE 16 -1 (-7650 3300)(-7900 3300);
WIRE 16 -1 (-7900 3250)(-7900 3300);
WIRE 16 -1 (-7650 3250)(-7900 3250);
WIRE 16 -1 (-7900 3200)(-7900 3250);
WIRE 16 -1 (-7650 3200)(-7900 3200);
WIRE 16 -1 (-7900 3150)(-7900 3200);
WIRE 16 -1 (-7650 3150)(-7900 3150);
WIRE 16 -1 (-7900 3100)(-7900 3150);
WIRE 16 -1 (-7650 3100)(-7900 3100);
WIRE 16 -1 (-7900 3050)(-7900 3100);
WIRE 16 -1 (-7650 3050)(-7900 3050);
WIRE 16 -1 (-7900 2800)(-7900 3050);
WIRE 16 -1 (-6675 2350)(-6675 2250);
WIRE 16 -1 (-1375 2500)(-1150 2500);
WIRE 16 -1 (-1150 2500)(-1150 2150);
WIRE 16 -1 (-1375 2150)(-1150 2150);
WIRE 16 -1 (-1150 2150)(-1150 2100);
WIRE 16 -1 (-1375 2100)(-1150 2100);
WIRE 16 -1 (-1150 2100)(-1150 2050);
WIRE 16 -1 (-1375 2050)(-1150 2050);
WIRE 16 -1 (-1150 2050)(-1150 2000);
WIRE 16 -1 (-1375 2000)(-1150 2000);
WIRE 16 -1 (-1150 2000)(-1150 1950);
WIRE 16 -1 (-1375 1950)(-1150 1950);
WIRE 16 -1 (-1150 1950)(-1150 1900);
WIRE 16 -1 (-1375 1900)(-1150 1900);
WIRE 16 -1 (-1150 1900)(-1150 1850);
WIRE 16 -1 (-1375 1850)(-1150 1850);
WIRE 16 -1 (-1150 1850)(-1150 1800);
WIRE 16 -1 (-1375 1800)(-1150 1800);
WIRE 16 -1 (-1150 1800)(-1150 1750);
WIRE 16 -1 (-1375 1750)(-1150 1750);
WIRE 16 -1 (-1150 1750)(-1150 1700);
WIRE 16 -1 (-1375 1700)(-1150 1700);
WIRE 16 -1 (-1150 1700)(-1150 1600);
WIRE 16 -1 (-1375 1600)(-1150 1600);
WIRE 16 -1 (-1150 1600)(-1150 1550);
WIRE 16 -1 (-1375 1550)(-1150 1550);
WIRE 16 -1 (-1150 1550)(-1150 1500);
WIRE 16 -1 (-1375 1500)(-1150 1500);
WIRE 16 -1 (-1150 1500)(-1150 1450);
WIRE 16 -1 (-1375 1450)(-1150 1450);
WIRE 16 -1 (-1150 1450)(-1150 1400);
WIRE 16 -1 (-1375 1400)(-1150 1400);
WIRE 16 -1 (-1150 1400)(-1150 1350);
WIRE 16 -1 (-1375 1350)(-1150 1350);
WIRE 16 -1 (-1150 1350)(-1150 1300);
WIRE 16 -1 (-1375 1300)(-1150 1300);
WIRE 16 -1 (-1150 1300)(-1150 1250);
WIRE 16 -1 (-1375 1250)(-1150 1250);
WIRE 16 -1 (-1150 1250)(-1150 1200);
WIRE 16 -1 (-1375 1200)(-1150 1200);
WIRE 16 -1 (-1150 1200)(-1150 1100);
WIRE 16 -1 (-2325 3050)(-2600 3050);
WIRE 16 -1 (-2600 3050)(-2600 3100);
WIRE 16 -1 (-2325 3100)(-2600 3100);
WIRE 16 -1 (-2600 3100)(-2600 3150);
WIRE 16 -1 (-2325 3150)(-2600 3150);
WIRE 16 -1 (-2600 3150)(-2600 3200);
WIRE 16 -1 (-2325 3200)(-2600 3200);
WIRE 16 -1 (-2600 3200)(-2600 3250);
WIRE 16 -1 (-2325 3250)(-2600 3250);
WIRE 16 -1 (-2600 3250)(-2600 3300);
WIRE 16 -1 (-2325 3300)(-2600 3300);
WIRE 16 -1 (-2600 3300)(-2600 3350);
WIRE 16 -1 (-2325 3350)(-2600 3350);
WIRE 16 -1 (-2600 3350)(-2600 3400);
WIRE 16 -1 (-2325 3400)(-2600 3400);
WIRE 16 -1 (-2600 3400)(-2600 3450);
WIRE 16 -1 (-2325 3450)(-2600 3450);
WIRE 16 -1 (-2600 3450)(-2600 3500);
WIRE 16 -1 (-2325 3500)(-2600 3500);
WIRE 16 -1 (-2600 3500)(-2600 3600);
WIRE 16 -1 (-2325 3600)(-2600 3600);
WIRE 16 -1 (-2600 3600)(-2600 3650);
WIRE 16 -1 (-2325 3650)(-2600 3650);
WIRE 16 -1 (-2600 3650)(-2600 3700);
WIRE 16 -1 (-2325 3700)(-2600 3700);
WIRE 16 -1 (-2600 3700)(-2600 3750);
WIRE 16 -1 (-2325 3750)(-2600 3750);
WIRE 16 -1 (-2600 3750)(-2600 3800);
WIRE 16 -1 (-2325 3800)(-2600 3800);
WIRE 16 -1 (-2600 3800)(-2600 3850);
WIRE 16 -1 (-2325 3850)(-2600 3850);
WIRE 16 -1 (-2600 3850)(-2600 3900);
WIRE 16 -1 (-2325 3900)(-2600 3900);
WIRE 16 -1 (-2600 3900)(-2600 3950);
WIRE 16 -1 (-2325 3950)(-2600 3950);
WIRE 16 -1 (-2600 3950)(-2600 4000);
WIRE 16 -1 (-2325 4000)(-2600 4000);
WIRE 16 -1 (-2600 4000)(-2600 4050);
WIRE 16 -1 (-2325 4050)(-2600 4050);
WIRE 16 -1 (-2325 2950)(-2700 2950);
WIRE 16 -1 (-2700 3250)(-2700 2950);
WIRE 16 -1 (-3050 3250)(-2700 3250);
WIRE 16 -1 (-3050 3250)(-3050 3150);
WIRE 16 -1 (-3050 3250)(-3400 3250);
WIRE 16 -1 (-3400 3150)(-3400 3250);
WIRE 16 -1 (-3400 3250)(-3400 3325);
WIRE 16 -1 (-2325 2900)(-3050 2900);
WIRE 16 -1 (-3050 3000)(-3050 2900);
WIRE 16 -1 (-3050 2900)(-3400 2900);
WIRE 16 -1 (-3400 2900)(-3400 3000);
WIRE 16 -1 (-3400 2875)(-3400 2900);
WIRE 16 -1 (-3550 2100)(-3550 2325);
WIRE 16 -1 (-3800 2100)(-3800 2375);
WIRE 16 -1 (-4025 4800)(-4025 4825);
WIRE 16 -1 (-4025 4825)(-4450 4825);
WIRE 16 -1 (-4450 4775)(-4450 4825);
WIRE 16 -1 (-4450 4825)(-4775 4825);
WIRE 16 -1 (-4775 4775)(-4775 4825);
WIRE 16 -1 (-4775 4825)(-4950 4825);
WIRE 16 -1 (-4950 4775)(-4950 4825);
WIRE 16 -1 (-4950 4900)(-4950 4825);
WIRE 16 -1 (-4025 4550)(-4025 4600);
WIRE 16 -1 (-4025 4550)(-4450 4550);
WIRE 16 -1 (-4450 4625)(-4450 4550);
WIRE 16 -1 (-4450 4550)(-4775 4550);
WIRE 16 -1 (-4775 4625)(-4775 4550);
WIRE 16 -1 (-4950 4550)(-4775 4550);
WIRE 16 -1 (-4950 4625)(-4950 4550);
WIRE 16 -1 (-4950 4550)(-4950 4475);
WIRE 16 -1 (-5575 3050)(-5575 3100);
WIRE 16 -1 (-5575 3050)(-5400 3050);
WIRE 16 -1 (-6025 3050)(-5575 3050);
WIRE 16 -1 (-6025 3100)(-5575 3100);
WIRE 16 -1 (-5575 3100)(-5575 3150);
WIRE 16 -1 (-6025 3150)(-5575 3150);
WIRE 16 -1 (-5575 3150)(-5575 3200);
WIRE 16 -1 (-6025 3200)(-5575 3200);
WIRE 16 -1 (-5575 3200)(-5575 3250);
WIRE 16 -1 (-6025 3250)(-5575 3250);
WIRE 16 -1 (-5575 3250)(-5575 3300);
WIRE 16 -1 (-5575 3300)(-5575 3350);
WIRE 16 -1 (-5575 3300)(-5400 3300);
WIRE 16 -1 (-6025 3300)(-5575 3300);
WIRE 16 -1 (-6025 3350)(-5575 3350);
WIRE 16 -1 (-5575 3350)(-5575 3400);
WIRE 16 -1 (-6025 3400)(-5575 3400);
WIRE 16 -1 (-5575 3400)(-5575 3450);
WIRE 16 -1 (-6025 3450)(-5575 3450);
WIRE 16 -1 (-5575 3450)(-5575 3500);
WIRE 16 -1 (-6025 3500)(-5575 3500);
WIRE 16 -1 (-5575 3500)(-5575 3550);
WIRE 16 -1 (-5575 3550)(-5575 3600);
WIRE 16 -1 (-5575 3550)(-5400 3550);
WIRE 16 -1 (-6025 3550)(-5575 3550);
WIRE 16 -1 (-6025 3600)(-5575 3600);
WIRE 16 -1 (-5575 3600)(-5575 3650);
WIRE 16 -1 (-6025 3650)(-5575 3650);
WIRE 16 -1 (-5575 3650)(-5575 3700);
WIRE 16 -1 (-6025 3700)(-5575 3700);
WIRE 16 -1 (-5575 3700)(-5575 3750);
WIRE 16 -1 (-6025 3750)(-5575 3750);
WIRE 16 -1 (-5575 3800)(-5575 3750);
WIRE 16 -1 (-5575 3800)(-5575 3850);
WIRE 16 -1 (-5575 3800)(-5400 3800);
WIRE 16 -1 (-6025 3800)(-5575 3800);
WIRE 16 -1 (-6025 3850)(-5575 3850);
WIRE 16 -1 (-5575 3850)(-5575 3900);
WIRE 16 -1 (-6025 3900)(-5575 3900);
WIRE 16 -1 (-5575 3900)(-5575 3950);
WIRE 16 -1 (-6025 3950)(-5575 3950);
WIRE 16 -1 (-5575 3950)(-5575 4000);
WIRE 16 -1 (-6025 4000)(-5575 4000);
WIRE 16 -1 (-5575 4000)(-5575 4050);
WIRE 16 -1 (-5575 4050)(-5575 4100);
WIRE 16 -1 (-5575 4050)(-5400 4050);
WIRE 16 -1 (-6025 4050)(-5575 4050);
WIRE 16 -1 (-6025 4100)(-5575 4100);
WIRE 16 -1 (-5575 4100)(-5575 4150);
WIRE 16 -1 (-6025 4150)(-5575 4150);
WIRE 16 -1 (-5575 4150)(-5575 4200);
WIRE 16 -1 (-6025 4200)(-5575 4200);
WIRE 16 -1 (-5575 4200)(-5575 4250);
WIRE 16 -1 (-6025 4250)(-5575 4250);
WIRE 16 -1 (-5575 4250)(-5575 4300);
WIRE 16 -1 (-5575 4525)(-5575 4300);
WIRE 16 -1 (-5575 4300)(-5400 4300);
WIRE 16 -1 (-6025 4300)(-5575 4300);
WIRE 16 -1 (-4550 2775)(-4550 2625);
WIRE 16 -1 (-4550 2625)(-4700 2625);
WIRE 16 -1 (-5200 4300)(-5000 4300);
WIRE 16 -1 (-5000 4050)(-5000 4300);
WIRE 16 -1 (-5200 4050)(-5000 4050);
WIRE 16 -1 (-5000 3800)(-5000 4050);
WIRE 16 -1 (-5200 3800)(-5000 3800);
WIRE 16 -1 (-5000 3550)(-5000 3800);
WIRE 16 -1 (-5200 3550)(-5000 3550);
WIRE 16 -1 (-5000 3300)(-5000 3550);
WIRE 16 -1 (-5200 3300)(-5000 3300);
WIRE 16 -1 (-5000 3050)(-5000 3300);
WIRE 16 -1 (-5200 3050)(-5000 3050);
WIRE 16 -1 (-5000 2975)(-5000 3050);
WIRE 16 -1 (-2325 2750)(-3800 2750);
FORCEPROP 2 LAST SIG_NAME BMC_M_VREFCA
J 0
(-3460 2760);
DISPLAY 0.680851 (-3460 2760);
PAINT ORANGE (-3460 2760);
FORCEPROP 2 LASTPROP $XR1 149 
J 0
(-3736 2760);
DISPLAY 0.638298 (-3736 2760);
PAINT MONO (-3736 2760);
FORCEPROP 2 LASTPROP $XR0 143 
J 0
(-3616 2760);
DISPLAY 0.638298 (-3616 2760);
PAINT MONO (-3616 2760);
WIRE 16 -1 (-3800 2750)(-3800 2575);
WIRE 16 -1 (-3550 2700)(-2325 2700);
FORCEPROP 2 LAST SIG_NAME BMC_ZQ
J 0
(-3435 2710);
DISPLAY 0.680851 (-3435 2710);
PAINT ORANGE (-3435 2710);
FORCEPROP 2 LASTPROP $XRERR UNIQUE?
J 0
(-3675 2710);
DISPLAY 0.638298 (-3675 2710);
PAINT MONO (-3675 2710);
DISPLAY INVISIBLE (-3675 2710);
WIRE 16 -1 (-3550 2700)(-3550 2525);
WIRE 16 -1 (-1375 2800)(-925 2800);
FORCEPROP 2 LAST SIG_NAME BMC_M_MALERT_N
J 0
(-1285 2810);
DISPLAY 0.680851 (-1285 2810);
PAINT ORANGE (-1285 2810);
WIRE 16 -1 (-1375 2850)(-925 2850);
FORCEPROP 2 LAST SIG_NAME BMC_M_RST_N
J 0
(-1260 2860);
DISPLAY 0.680851 (-1260 2860);
PAINT ORANGE (-1260 2860);
WIRE 16 -1 (-1375 2900)(-925 2900);
FORCEPROP 2 LAST SIG_NAME BMC_M_CS_N
J 0
(-1260 2910);
DISPLAY 0.680851 (-1260 2910);
PAINT ORANGE (-1260 2910);
WIRE 16 -1 (-1375 2950)(-925 2950);
FORCEPROP 2 LAST SIG_NAME BMC_M_MACT_N
J 0
(-1260 2960);
DISPLAY 0.680851 (-1260 2960);
PAINT ORANGE (-1260 2960);
WIRE 16 -1 (-1375 4050)(-925 4050);
FORCEPROP 2 LAST SIG_NAME BMC_M_A0
J 0
(-1260 4060);
DISPLAY 0.680851 (-1260 4060);
PAINT ORANGE (-1260 4060);
WIRE 16 -1 (-1375 4000)(-925 4000);
FORCEPROP 2 LAST SIG_NAME BMC_M_A1
J 0
(-1260 4010);
DISPLAY 0.680851 (-1260 4010);
PAINT ORANGE (-1260 4010);
WIRE 16 -1 (-1375 3950)(-925 3950);
FORCEPROP 2 LAST SIG_NAME BMC_M_A2
J 0
(-1260 3960);
DISPLAY 0.680851 (-1260 3960);
PAINT ORANGE (-1260 3960);
WIRE 16 -1 (-1375 3850)(-925 3850);
FORCEPROP 2 LAST SIG_NAME BMC_M_A4
J 0
(-1260 3860);
DISPLAY 0.680851 (-1260 3860);
PAINT ORANGE (-1260 3860);
WIRE 16 -1 (-1375 3800)(-925 3800);
FORCEPROP 2 LAST SIG_NAME BMC_M_A5
J 0
(-1260 3810);
DISPLAY 0.680851 (-1260 3810);
PAINT ORANGE (-1260 3810);
WIRE 16 -1 (-1375 3900)(-925 3900);
FORCEPROP 2 LAST SIG_NAME BMC_M_A3
J 0
(-1260 3910);
DISPLAY 0.680851 (-1260 3910);
PAINT ORANGE (-1260 3910);
WIRE 16 -1 (-1375 3750)(-925 3750);
FORCEPROP 2 LAST SIG_NAME BMC_M_A6
J 0
(-1260 3760);
DISPLAY 0.680851 (-1260 3760);
PAINT ORANGE (-1260 3760);
WIRE 16 -1 (-1375 3700)(-925 3700);
FORCEPROP 2 LAST SIG_NAME BMC_M_A7
J 0
(-1260 3710);
DISPLAY 0.680851 (-1260 3710);
PAINT ORANGE (-1260 3710);
WIRE 16 -1 (-1375 3650)(-925 3650);
FORCEPROP 2 LAST SIG_NAME BMC_M_A8
J 0
(-1260 3660);
DISPLAY 0.680851 (-1260 3660);
PAINT ORANGE (-1260 3660);
WIRE 16 -1 (-1375 3600)(-925 3600);
FORCEPROP 2 LAST SIG_NAME BMC_M_A9
J 0
(-1260 3610);
DISPLAY 0.680851 (-1260 3610);
PAINT ORANGE (-1260 3610);
WIRE 16 -1 (-1375 3550)(-925 3550);
FORCEPROP 2 LAST SIG_NAME BMC_M_A10
J 0
(-1260 3560);
DISPLAY 0.680851 (-1260 3560);
PAINT ORANGE (-1260 3560);
WIRE 16 -1 (-1375 3150)(-925 3150);
FORCEPROP 2 LAST SIG_NAME BMC_M_CKE
J 0
(-1260 3160);
DISPLAY 0.680851 (-1260 3160);
PAINT ORANGE (-1260 3160);
WIRE 16 -1 (-1375 3050)(-925 3050);
FORCEPROP 2 LAST SIG_NAME BMC_M_CLK_DN
J 0
(-1285 3060);
DISPLAY 0.680851 (-1285 3060);
PAINT ORANGE (-1285 3060);
WIRE 16 -1 (-1375 2700)(-925 2700);
FORCEPROP 2 LAST SIG_NAME BMC_M_ODT
J 0
(-1260 2710);
DISPLAY 0.680851 (-1260 2710);
PAINT ORANGE (-1260 2710);
WIRE 16 -1 (-6775 725)(-6775 825);
WIRE 16 -1 (-6775 825)(-6450 825);
WIRE 16 -1 (-6775 925)(-6775 825);
WIRE 16 -1 (-6450 825)(-6175 825);
WIRE 16 -1 (-6450 725)(-6450 825);
WIRE 16 -1 (-5725 825)(-6175 825);
FORCEPROP 2 LAST SIG_NAME BMC_M_VREFCA
J 0
(-6110 835);
DISPLAY 0.680851 (-6110 835);
PAINT ORANGE (-6110 835);
FORCEPROP 2 LASTPROP $XR1 149 
J 0
(-5575 825);
DISPLAY 0.638298 (-5575 825);
PAINT MONO (-5575 825);
FORCEPROP 2 LASTPROP $XR0 143 
J 0
(-5695 825);
DISPLAY 0.638298 (-5695 825);
PAINT MONO (-5695 825);
WIRE 16 -1 (-6175 950)(-6175 825);
WIRE 16 -1 (-6175 725)(-6175 825);
WIRE 16 -1 (-4675 850)(-4675 900);
WIRE 16 -1 (-4675 1000)(-4675 900);
WIRE 16 -1 (-4675 900)(-5125 900);
FORCEPROP 2 LAST SIG_NAME BMC_M_PAR
J 0
(-5110 910);
DISPLAY 0.680851 (-5110 910);
PAINT ORANGE (-5110 910);
FORCEPROP 2 LASTPROP $XR0 149 
J 0
(-5221 900);
DISPLAY 0.638298 (-5221 900);
PAINT MONO (-5221 900);
WIRE 16 -1 (-6200 2025)(-6200 2150);
FORCEPROP 2 LAST SIG_NAME FM_HEARTBEAT_LED
J 0
(-6185 2110);
DISPLAY 0.617021 (-6185 2110);
PAINT ORANGE (-6185 2110);
FORCEPROP 2 LASTPROP $XRERR UNIQUE?
J 0
(-6425 2110);
DISPLAY 0.638298 (-6425 2110);
PAINT MONO (-6425 2110);
DISPLAY INVISIBLE (-6425 2110);
WIRE 16 -1 (-6200 2150)(-5800 2150);
WIRE 16 -1 (-6200 2150)(-6200 2225);
WIRE 16 -1 (-4900 2625)(-5300 2625);
FORCEPROP 2 LAST SIG_NAME FM_HEARTBEAT_LED_A
J 0
(-5310 2635);
DISPLAY 0.617021 (-5310 2635);
PAINT ORANGE (-5310 2635);
FORCEPROP 2 LASTPROP $XRERR UNIQUE?
J 0
(-5550 2635);
DISPLAY 0.638298 (-5550 2635);
PAINT MONO (-5550 2635);
DISPLAY INVISIBLE (-5550 2635);
WIRE 16 -1 (-2325 4600)(-1725 4600);
FORCEPROP 2 LAST SIG_NAME RST_BMC_DDR3_R_N
J 0
(-2260 4610);
DISPLAY 0.617021 (-2260 4610);
PAINT ORANGE (-2260 4610);
FORCEPROP 2 LASTPROP $XRERR UNIQUE?
J 0
(-2500 4610);
DISPLAY 0.638298 (-2500 4610);
PAINT MONO (-2500 4610);
DISPLAY INVISIBLE (-2500 4610);
WIRE 16 -1 (-1725 4600)(-1475 4600);
WIRE 16 -1 (-1725 4675)(-1725 4600);
WIRE 16 -1 (-7175 1725)(-6675 1725);
FORCEPROP 2 LAST SIG_NAME FM_BMC_HEARTBEAT_N
J 0
(-7135 1735);
DISPLAY 0.617021 (-7135 1735);
PAINT ORANGE (-7135 1735);
WIRE 16 -1 (-6675 2050)(-6675 1725);
WIRE 16 -1 (-6675 1725)(-6400 1725);
WIRE 16 -1 (-4125 575)(-3550 575);
FORCEPROP 2 LAST SIG_NAME BMC_M_CLK_DN
J 0
(-4060 585);
DISPLAY 0.680851 (-4060 585);
PAINT ORANGE (-4060 585);
FORCEPROP 2 LASTPROP $XR1 149 
J 0
(-4341 575);
DISPLAY 0.638298 (-4341 575);
PAINT MONO (-4341 575);
FORCEPROP 2 LASTPROP $XR0 143 
J 0
(-4221 575);
DISPLAY 0.638298 (-4221 575);
PAINT MONO (-4221 575);
WIRE 16 -1 (-3550 575)(-3550 650);
WIRE 16 -1 (-3550 900)(-3550 975);
WIRE 16 -1 (-4125 975)(-3550 975);
FORCEPROP 2 LAST SIG_NAME BMC_M_CLK_DP
J 0
(-4060 985);
DISPLAY 0.680851 (-4060 985);
PAINT ORANGE (-4060 985);
FORCEPROP 2 LASTPROP $XR1 149 
J 0
(-4341 975);
DISPLAY 0.638298 (-4341 975);
PAINT MONO (-4341 975);
FORCEPROP 2 LASTPROP $XR0 143 
J 0
(-4221 975);
DISPLAY 0.638298 (-4221 975);
PAINT MONO (-4221 975);
WIRE 16 -1 (-400 4600)(-1275 4600);
FORCEPROP 2 LAST SIG_NAME BMC_M_RST_N
J 0
(-910 4610);
DISPLAY 0.680851 (-910 4610);
PAINT ORANGE (-910 4610);
WIRE 16 -1 (-1375 2400)(-875 2400);
FORCEPROP 2 LAST SIG_NAME BMC_M_PAR
J 0
(-1085 2410);
DISPLAY 0.680851 (-1085 2410);
PAINT ORANGE (-1085 2410);
WIRE 16 -1 (-3300 4600)(-2575 4600);
FORCEPROP 2 LAST SIG_NAME RST_BMC_DDR3_BUF_IN_N
J 0
(-3260 4610);
DISPLAY 0.617021 (-3260 4610);
PAINT ORANGE (-3260 4610);
WIRE 3 2175 (-3700 4350)(-25 4350);
WIRE 3 2175 (-3700 5050)(-3700 4350);
WIRE 3 2175 (-25 5050)(-25 4350);
WIRE 3 2175 (-3700 5050)(-25 5050);
WIRE 16 -1 (-1375 3250)(-925 3250);
FORCEPROP 2 LAST SIG_NAME BMC_M_RAS_N
J 0
(-1260 3260);
DISPLAY 0.680851 (-1260 3260);
PAINT ORANGE (-1260 3260);
WIRE 16 -1 (-1375 2600)(-925 2600);
FORCEPROP 2 LAST SIG_NAME BMC_M_BG0
J 0
(-1260 2610);
DISPLAY 0.680851 (-1260 2610);
PAINT ORANGE (-1260 2610);
WIRE 16 -1 (-1375 3500)(-925 3500);
FORCEPROP 2 LAST SIG_NAME BMC_M_A11
J 0
(-1260 3510);
DISPLAY 0.680851 (-1260 3510);
PAINT ORANGE (-1260 3510);
WIRE 16 -1 (-1375 3450)(-925 3450);
FORCEPROP 2 LAST SIG_NAME BMC_M_A12
J 0
(-1260 3460);
DISPLAY 0.680851 (-1260 3460);
PAINT ORANGE (-1260 3460);
WIRE 16 -1 (-1375 3400)(-925 3400);
FORCEPROP 2 LAST SIG_NAME BMC_M_A13
J 0
(-1260 3410);
DISPLAY 0.680851 (-1260 3410);
PAINT ORANGE (-1260 3410);
WIRE 16 -1 (-1375 3350)(-925 3350);
FORCEPROP 2 LAST SIG_NAME BMC_M_WE_N
J 0
(-1260 3360);
DISPLAY 0.680851 (-1260 3360);
PAINT ORANGE (-1260 3360);
WIRE 16 -1 (-1375 3300)(-925 3300);
FORCEPROP 2 LAST SIG_NAME BMC_M_CAS_N
J 0
(-1260 3310);
DISPLAY 0.680851 (-1260 3310);
PAINT ORANGE (-1260 3310);
WIRE 16 -1 (-1375 3100)(-925 3100);
FORCEPROP 2 LAST SIG_NAME BMC_M_CLK_DP
J 0
(-1260 3110);
DISPLAY 0.680851 (-1260 3110);
PAINT ORANGE (-1260 3110);
WIRE 16 -1 (-5500 2625)(-5600 2625);
FORCEPROP 2 LAST SIG_NAME FM_HEARTBEAT_LED_K
J 0
(-5910 2635);
DISPLAY 0.617021 (-5910 2635);
PAINT ORANGE (-5910 2635);
FORCEPROP 2 LASTPROP $XRERR UNIQUE?
J 0
(-6150 2635);
DISPLAY 0.638298 (-6150 2635);
PAINT MONO (-6150 2635);
DISPLAY INVISIBLE (-6150 2635);
WIRE 16 -1 (-5600 2625)(-5600 2450);
WIRE 16 -1 (-2925 2600)(-2325 2600);
FORCEPROP 2 LAST SIG_NAME BMC_M_DQ8
J 0
(-2810 2610);
DISPLAY 0.680851 (-2810 2610);
PAINT ORANGE (-2810 2610);
WIRE 16 -1 (-2925 2550)(-2325 2550);
FORCEPROP 2 LAST SIG_NAME BMC_M_DQ9
J 0
(-2810 2560);
DISPLAY 0.680851 (-2810 2560);
PAINT ORANGE (-2810 2560);
WIRE 16 -1 (-2925 2500)(-2325 2500);
FORCEPROP 2 LAST SIG_NAME BMC_M_DQ10
J 0
(-2810 2510);
DISPLAY 0.680851 (-2810 2510);
PAINT ORANGE (-2810 2510);
WIRE 16 -1 (-2925 2450)(-2325 2450);
FORCEPROP 2 LAST SIG_NAME BMC_M_DQ11
J 0
(-2810 2460);
DISPLAY 0.680851 (-2810 2460);
PAINT ORANGE (-2810 2460);
WIRE 16 -1 (-2925 2400)(-2325 2400);
FORCEPROP 2 LAST SIG_NAME BMC_M_DQ12
J 0
(-2810 2410);
DISPLAY 0.680851 (-2810 2410);
PAINT ORANGE (-2810 2410);
WIRE 16 -1 (-2925 2350)(-2325 2350);
FORCEPROP 2 LAST SIG_NAME BMC_M_DQ13
J 0
(-2810 2360);
DISPLAY 0.680851 (-2810 2360);
PAINT ORANGE (-2810 2360);
WIRE 16 -1 (-2925 2300)(-2325 2300);
FORCEPROP 2 LAST SIG_NAME BMC_M_DQ14
J 0
(-2810 2310);
DISPLAY 0.680851 (-2810 2310);
PAINT ORANGE (-2810 2310);
WIRE 16 -1 (-2325 2250)(-2925 2250);
FORCEPROP 2 LAST SIG_NAME BMC_M_DQ15
J 0
(-2810 2260);
DISPLAY 0.680851 (-2810 2260);
PAINT ORANGE (-2810 2260);
WIRE 16 -1 (-2925 2150)(-2325 2150);
FORCEPROP 2 LAST SIG_NAME BMC_M_DQ0
J 0
(-2810 2160);
DISPLAY 0.680851 (-2810 2160);
PAINT ORANGE (-2810 2160);
WIRE 16 -1 (-2925 2100)(-2325 2100);
FORCEPROP 2 LAST SIG_NAME BMC_M_DQ1
J 0
(-2810 2110);
DISPLAY 0.680851 (-2810 2110);
PAINT ORANGE (-2810 2110);
WIRE 16 -1 (-2925 2050)(-2325 2050);
FORCEPROP 2 LAST SIG_NAME BMC_M_DQ2
J 0
(-2810 2060);
DISPLAY 0.680851 (-2810 2060);
PAINT ORANGE (-2810 2060);
WIRE 16 -1 (-2925 2000)(-2325 2000);
FORCEPROP 2 LAST SIG_NAME BMC_M_DQ3
J 0
(-2810 2010);
DISPLAY 0.680851 (-2810 2010);
PAINT ORANGE (-2810 2010);
WIRE 16 -1 (-2925 1950)(-2325 1950);
FORCEPROP 2 LAST SIG_NAME BMC_M_DQ4
J 0
(-2810 1960);
DISPLAY 0.680851 (-2810 1960);
PAINT ORANGE (-2810 1960);
WIRE 16 -1 (-2925 1850)(-2325 1850);
FORCEPROP 2 LAST SIG_NAME BMC_M_DQ6
J 0
(-2810 1860);
DISPLAY 0.680851 (-2810 1860);
PAINT ORANGE (-2810 1860);
WIRE 16 -1 (-2925 1900)(-2325 1900);
FORCEPROP 2 LAST SIG_NAME BMC_M_DQ5
J 0
(-2810 1910);
DISPLAY 0.680851 (-2810 1910);
PAINT ORANGE (-2810 1910);
WIRE 16 -1 (-2925 1800)(-2325 1800);
FORCEPROP 2 LAST SIG_NAME BMC_M_DQ7
J 0
(-2810 1810);
DISPLAY 0.680851 (-2810 1810);
PAINT ORANGE (-2810 1810);
WIRE 16 -1 (-2325 1700)(-2925 1700);
FORCEPROP 2 LAST SIG_NAME BMC_M_DQS1_DN
J 0
(-2885 1710);
DISPLAY 0.680851 (-2885 1710);
PAINT ORANGE (-2885 1710);
WIRE 16 -1 (-2325 1600)(-2925 1600);
FORCEPROP 2 LAST SIG_NAME BMC_M_DQS0_DN
J 0
(-2885 1610);
DISPLAY 0.680851 (-2885 1610);
PAINT ORANGE (-2885 1610);
WIRE 16 -1 (-2325 1650)(-2925 1650);
FORCEPROP 2 LAST SIG_NAME BMC_M_DQS1_DP
J 0
(-2885 1660);
DISPLAY 0.680851 (-2885 1660);
PAINT ORANGE (-2885 1660);
WIRE 16 -1 (-2325 1550)(-2925 1550);
FORCEPROP 2 LAST SIG_NAME BMC_M_DQS0_DP
J 0
(-2885 1560);
DISPLAY 0.680851 (-2885 1560);
PAINT ORANGE (-2885 1560);
WIRE 16 -1 (-2925 1450)(-2325 1450);
FORCEPROP 2 LAST SIG_NAME BMC_M_DM1
J 0
(-2810 1460);
DISPLAY 0.680851 (-2810 1460);
PAINT ORANGE (-2810 1460);
WIRE 16 -1 (-2925 1400)(-2325 1400);
FORCEPROP 2 LAST SIG_NAME BMC_M_DM0
J 0
(-2810 1410);
DISPLAY 0.680851 (-2810 1410);
PAINT ORANGE (-2810 1410);
WIRE 16 -1 (-2925 1250)(-2325 1250);
FORCEPROP 2 LAST SIG_NAME BMC_M_BA0
J 0
(-2810 1260);
DISPLAY 0.680851 (-2810 1260);
PAINT ORANGE (-2810 1260);
WIRE 16 -1 (-2925 1200)(-2325 1200);
FORCEPROP 2 LAST SIG_NAME BMC_M_BA1
J 0
(-2810 1210);
DISPLAY 0.680851 (-2810 1210);
PAINT ORANGE (-2810 1210);
WIRE 16 -1 (-7400 3900)(-6275 3900);
FORCEPROP 2 LAST SIG_NAME BMC_M_BA0
J 0
(-6835 3910);
DISPLAY 0.680851 (-6835 3910);
PAINT ORANGE (-6835 3910);
FORCEPROP 2 LASTPROP $XR1 149 
J 0
(-7105 3910);
DISPLAY 0.638298 (-7105 3910);
PAINT MONO (-7105 3910);
FORCEPROP 2 LASTPROP $XR0 143 
J 0
(-7105 3910);
DISPLAY 0.638298 (-7105 3910);
PAINT MONO (-7105 3910);
WIRE 16 -1 (-7400 3850)(-6275 3850);
FORCEPROP 2 LAST SIG_NAME BMC_M_BA1
J 0
(-6835 3860);
DISPLAY 0.680851 (-6835 3860);
PAINT ORANGE (-6835 3860);
FORCEPROP 2 LASTPROP $XR1 149 
J 0
(-7105 3860);
DISPLAY 0.638298 (-7105 3860);
PAINT MONO (-7105 3860);
FORCEPROP 2 LASTPROP $XR0 143 
J 0
(-7105 3860);
DISPLAY 0.638298 (-7105 3860);
PAINT MONO (-7105 3860);
WIRE 16 -1 (-7400 3800)(-6275 3800);
FORCEPROP 2 LAST SIG_NAME BMC_M_BG0
J 0
(-6835 3810);
DISPLAY 0.680851 (-6835 3810);
PAINT ORANGE (-6835 3810);
FORCEPROP 2 LASTPROP $XR1 149 
J 0
(-7105 3810);
DISPLAY 0.638298 (-7105 3810);
PAINT MONO (-7105 3810);
FORCEPROP 2 LASTPROP $XR0 143 
J 0
(-7105 3810);
DISPLAY 0.638298 (-7105 3810);
PAINT MONO (-7105 3810);
WIRE 16 -1 (-7400 3750)(-6275 3750);
FORCEPROP 2 LAST SIG_NAME BMC_M_A0
J 0
(-6835 3760);
DISPLAY 0.680851 (-6835 3760);
PAINT ORANGE (-6835 3760);
FORCEPROP 2 LASTPROP $XR1 149 
J 0
(-7105 3760);
DISPLAY 0.638298 (-7105 3760);
PAINT MONO (-7105 3760);
FORCEPROP 2 LASTPROP $XR0 143 
J 0
(-7105 3760);
DISPLAY 0.638298 (-7105 3760);
PAINT MONO (-7105 3760);
WIRE 16 -1 (-7400 3600)(-6275 3600);
FORCEPROP 2 LAST SIG_NAME BMC_M_A3
J 0
(-6835 3610);
DISPLAY 0.680851 (-6835 3610);
PAINT ORANGE (-6835 3610);
FORCEPROP 2 LASTPROP $XR1 149 
J 0
(-7105 3610);
DISPLAY 0.638298 (-7105 3610);
PAINT MONO (-7105 3610);
FORCEPROP 2 LASTPROP $XR0 143 
J 0
(-7105 3610);
DISPLAY 0.638298 (-7105 3610);
PAINT MONO (-7105 3610);
WIRE 16 -1 (-7400 3650)(-6275 3650);
FORCEPROP 2 LAST SIG_NAME BMC_M_A2
J 0
(-6835 3660);
DISPLAY 0.680851 (-6835 3660);
PAINT ORANGE (-6835 3660);
FORCEPROP 2 LASTPROP $XR1 149 
J 0
(-7105 3660);
DISPLAY 0.638298 (-7105 3660);
PAINT MONO (-7105 3660);
FORCEPROP 2 LASTPROP $XR0 143 
J 0
(-7105 3660);
DISPLAY 0.638298 (-7105 3660);
PAINT MONO (-7105 3660);
WIRE 16 -1 (-7400 3500)(-6275 3500);
FORCEPROP 2 LAST SIG_NAME BMC_M_A5
J 0
(-6835 3510);
DISPLAY 0.680851 (-6835 3510);
PAINT ORANGE (-6835 3510);
FORCEPROP 2 LASTPROP $XR1 149 
J 0
(-7105 3510);
DISPLAY 0.638298 (-7105 3510);
PAINT MONO (-7105 3510);
FORCEPROP 2 LASTPROP $XR0 143 
J 0
(-7105 3510);
DISPLAY 0.638298 (-7105 3510);
PAINT MONO (-7105 3510);
WIRE 16 -1 (-7400 3550)(-6275 3550);
FORCEPROP 2 LAST SIG_NAME BMC_M_A4
J 0
(-6835 3560);
DISPLAY 0.680851 (-6835 3560);
PAINT ORANGE (-6835 3560);
FORCEPROP 2 LASTPROP $XR1 149 
J 0
(-7105 3560);
DISPLAY 0.638298 (-7105 3560);
PAINT MONO (-7105 3560);
FORCEPROP 2 LASTPROP $XR0 143 
J 0
(-7105 3560);
DISPLAY 0.638298 (-7105 3560);
PAINT MONO (-7105 3560);
WIRE 16 -1 (-7400 3450)(-6275 3450);
FORCEPROP 2 LAST SIG_NAME BMC_M_A6
J 0
(-6835 3460);
DISPLAY 0.680851 (-6835 3460);
PAINT ORANGE (-6835 3460);
FORCEPROP 2 LASTPROP $XR1 149 
J 0
(-7105 3460);
DISPLAY 0.638298 (-7105 3460);
PAINT MONO (-7105 3460);
FORCEPROP 2 LASTPROP $XR0 143 
J 0
(-7105 3460);
DISPLAY 0.638298 (-7105 3460);
PAINT MONO (-7105 3460);
WIRE 16 -1 (-7400 3350)(-6275 3350);
FORCEPROP 2 LAST SIG_NAME BMC_M_A8
J 0
(-6835 3360);
DISPLAY 0.680851 (-6835 3360);
PAINT ORANGE (-6835 3360);
FORCEPROP 2 LASTPROP $XR1 149 
J 0
(-7105 3360);
DISPLAY 0.638298 (-7105 3360);
PAINT MONO (-7105 3360);
FORCEPROP 2 LASTPROP $XR0 143 
J 0
(-7105 3360);
DISPLAY 0.638298 (-7105 3360);
PAINT MONO (-7105 3360);
WIRE 16 -1 (-7400 4300)(-6275 4300);
FORCEPROP 2 LAST SIG_NAME BMC_M_CKE
J 0
(-6835 4310);
DISPLAY 0.680851 (-6835 4310);
PAINT ORANGE (-6835 4310);
FORCEPROP 2 LASTPROP $XR1 149 
J 0
(-7105 4310);
DISPLAY 0.638298 (-7105 4310);
PAINT MONO (-7105 4310);
FORCEPROP 2 LASTPROP $XR0 143 
J 0
(-7105 4310);
DISPLAY 0.638298 (-7105 4310);
PAINT MONO (-7105 4310);
WIRE 16 -1 (-7400 4250)(-6275 4250);
FORCEPROP 2 LAST SIG_NAME BMC_M_ODT
J 0
(-6835 4260);
DISPLAY 0.680851 (-6835 4260);
PAINT ORANGE (-6835 4260);
FORCEPROP 2 LASTPROP $XR1 149 
J 0
(-7105 4260);
DISPLAY 0.638298 (-7105 4260);
PAINT MONO (-7105 4260);
FORCEPROP 2 LASTPROP $XR0 143 
J 0
(-7105 4260);
DISPLAY 0.638298 (-7105 4260);
PAINT MONO (-7105 4260);
WIRE 16 -1 (-7400 4200)(-6275 4200);
FORCEPROP 2 LAST SIG_NAME BMC_M_RST_N
J 0
(-6835 4210);
DISPLAY 0.680851 (-6835 4210);
PAINT ORANGE (-6835 4210);
FORCEPROP 2 LASTPROP $XR1 149 
J 0
(-7105 4210);
DISPLAY 0.638298 (-7105 4210);
PAINT MONO (-7105 4210);
FORCEPROP 2 LASTPROP $XR0 146 
J 0
(-7105 4210);
DISPLAY 0.638298 (-7105 4210);
PAINT MONO (-7105 4210);
WIRE 16 -1 (-7400 4150)(-6275 4150);
FORCEPROP 2 LAST SIG_NAME BMC_M_MALERT_N
J 0
(-6860 4160);
DISPLAY 0.680851 (-6860 4160);
PAINT ORANGE (-6860 4160);
FORCEPROP 2 LASTPROP $XR1 149 
J 0
(-7130 4160);
DISPLAY 0.638298 (-7130 4160);
PAINT MONO (-7130 4160);
FORCEPROP 2 LASTPROP $XR0 146 
J 0
(-7055 4160);
DISPLAY 0.638298 (-7055 4160);
PAINT MONO (-7055 4160);
WIRE 16 -1 (-7400 4100)(-6275 4100);
FORCEPROP 2 LAST SIG_NAME BMC_M_CS_N
J 0
(-6835 4110);
DISPLAY 0.680851 (-6835 4110);
PAINT ORANGE (-6835 4110);
FORCEPROP 2 LASTPROP $XR1 149 
J 0
(-7105 4110);
DISPLAY 0.638298 (-7105 4110);
PAINT MONO (-7105 4110);
FORCEPROP 2 LASTPROP $XR0 143 
J 0
(-7105 4110);
DISPLAY 0.638298 (-7105 4110);
PAINT MONO (-7105 4110);
WIRE 16 -1 (-7400 4050)(-6275 4050);
FORCEPROP 2 LAST SIG_NAME BMC_M_RAS_N
J 0
(-6835 4060);
DISPLAY 0.680851 (-6835 4060);
PAINT ORANGE (-6835 4060);
FORCEPROP 2 LASTPROP $XR1 149 
J 0
(-7105 4060);
DISPLAY 0.638298 (-7105 4060);
PAINT MONO (-7105 4060);
FORCEPROP 2 LASTPROP $XR0 143 
J 0
(-7105 4060);
DISPLAY 0.638298 (-7105 4060);
PAINT MONO (-7105 4060);
WIRE 16 -1 (-7400 4000)(-6275 4000);
FORCEPROP 2 LAST SIG_NAME BMC_M_CAS_N
J 0
(-6835 4010);
DISPLAY 0.680851 (-6835 4010);
PAINT ORANGE (-6835 4010);
FORCEPROP 2 LASTPROP $XR1 149 
J 0
(-7105 4010);
DISPLAY 0.638298 (-7105 4010);
PAINT MONO (-7105 4010);
FORCEPROP 2 LASTPROP $XR0 143 
J 0
(-7105 4010);
DISPLAY 0.638298 (-7105 4010);
PAINT MONO (-7105 4010);
WIRE 16 -1 (-7400 3950)(-6275 3950);
FORCEPROP 2 LAST SIG_NAME BMC_M_WE_N
J 0
(-6835 3960);
DISPLAY 0.680851 (-6835 3960);
PAINT ORANGE (-6835 3960);
FORCEPROP 2 LASTPROP $XR1 149 
J 0
(-7105 3960);
DISPLAY 0.638298 (-7105 3960);
PAINT MONO (-7105 3960);
FORCEPROP 2 LASTPROP $XR0 143 
J 0
(-7105 3960);
DISPLAY 0.638298 (-7105 3960);
PAINT MONO (-7105 3960);
WIRE 16 -1 (-7400 3700)(-6275 3700);
FORCEPROP 2 LAST SIG_NAME BMC_M_A1
J 0
(-6835 3710);
DISPLAY 0.680851 (-6835 3710);
PAINT ORANGE (-6835 3710);
FORCEPROP 2 LASTPROP $XR1 149 
J 0
(-7105 3710);
DISPLAY 0.638298 (-7105 3710);
PAINT MONO (-7105 3710);
FORCEPROP 2 LASTPROP $XR0 143 
J 0
(-7105 3710);
DISPLAY 0.638298 (-7105 3710);
PAINT MONO (-7105 3710);
WIRE 16 -1 (-7400 3400)(-6275 3400);
FORCEPROP 2 LAST SIG_NAME BMC_M_A7
J 0
(-6835 3410);
DISPLAY 0.680851 (-6835 3410);
PAINT ORANGE (-6835 3410);
FORCEPROP 2 LASTPROP $XR1 149 
J 0
(-7105 3410);
DISPLAY 0.638298 (-7105 3410);
PAINT MONO (-7105 3410);
FORCEPROP 2 LASTPROP $XR0 143 
J 0
(-7105 3410);
DISPLAY 0.638298 (-7105 3410);
PAINT MONO (-7105 3410);
WIRE 16 -1 (-7400 3300)(-6275 3300);
FORCEPROP 2 LAST SIG_NAME BMC_M_A9
J 0
(-6835 3310);
DISPLAY 0.680851 (-6835 3310);
PAINT ORANGE (-6835 3310);
FORCEPROP 2 LASTPROP $XR1 149 
J 0
(-7105 3310);
DISPLAY 0.638298 (-7105 3310);
PAINT MONO (-7105 3310);
FORCEPROP 2 LASTPROP $XR0 143 
J 0
(-7105 3310);
DISPLAY 0.638298 (-7105 3310);
PAINT MONO (-7105 3310);
WIRE 16 -1 (-7400 3250)(-6275 3250);
FORCEPROP 2 LAST SIG_NAME BMC_M_A10
J 0
(-6835 3260);
DISPLAY 0.680851 (-6835 3260);
PAINT ORANGE (-6835 3260);
FORCEPROP 2 LASTPROP $XR1 149 
J 0
(-7105 3260);
DISPLAY 0.638298 (-7105 3260);
PAINT MONO (-7105 3260);
FORCEPROP 2 LASTPROP $XR0 143 
J 0
(-7105 3260);
DISPLAY 0.638298 (-7105 3260);
PAINT MONO (-7105 3260);
WIRE 16 -1 (-7400 3200)(-6275 3200);
FORCEPROP 2 LAST SIG_NAME BMC_M_A11
J 0
(-6835 3210);
DISPLAY 0.680851 (-6835 3210);
PAINT ORANGE (-6835 3210);
FORCEPROP 2 LASTPROP $XR1 149 
J 0
(-7105 3210);
DISPLAY 0.638298 (-7105 3210);
PAINT MONO (-7105 3210);
FORCEPROP 2 LASTPROP $XR0 143 
J 0
(-7105 3210);
DISPLAY 0.638298 (-7105 3210);
PAINT MONO (-7105 3210);
WIRE 16 -1 (-7400 3150)(-6275 3150);
FORCEPROP 2 LAST SIG_NAME BMC_M_A12
J 0
(-6835 3160);
DISPLAY 0.680851 (-6835 3160);
PAINT ORANGE (-6835 3160);
FORCEPROP 2 LASTPROP $XR1 149 
J 0
(-7105 3160);
DISPLAY 0.638298 (-7105 3160);
PAINT MONO (-7105 3160);
FORCEPROP 2 LASTPROP $XR0 143 
J 0
(-7105 3160);
DISPLAY 0.638298 (-7105 3160);
PAINT MONO (-7105 3160);
WIRE 16 -1 (-7400 3100)(-6275 3100);
FORCEPROP 2 LAST SIG_NAME BMC_M_A13
J 0
(-6835 3110);
DISPLAY 0.680851 (-6835 3110);
PAINT ORANGE (-6835 3110);
FORCEPROP 2 LASTPROP $XR1 149 
J 0
(-7105 3110);
DISPLAY 0.638298 (-7105 3110);
PAINT MONO (-7105 3110);
FORCEPROP 2 LASTPROP $XR0 143 
J 0
(-7105 3110);
DISPLAY 0.638298 (-7105 3110);
PAINT MONO (-7105 3110);
WIRE 16 -1 (-7400 3050)(-6275 3050);
FORCEPROP 2 LAST SIG_NAME BMC_M_MACT_N
J 0
(-6835 3060);
DISPLAY 0.680851 (-6835 3060);
PAINT ORANGE (-6835 3060);
FORCEPROP 2 LASTPROP $XR1 149 
J 0
(-7105 3060);
DISPLAY 0.638298 (-7105 3060);
PAINT MONO (-7105 3060);
FORCEPROP 2 LASTPROP $XR0 143 
J 0
(-7105 3060);
DISPLAY 0.638298 (-7105 3060);
PAINT MONO (-7105 3060);
DOT 1 (-1150 1250);
DOT 1 (-3400 3250);
DOT 1 (-3050 3250);
DOT 1 (-3050 2900);
DOT 1 (-2600 3450);
DOT 1 (-2600 3500);
DOT 1 (-6775 825);
DOT 1 (-6675 1725);
DOT 1 (-6450 325);
DOT 1 (-6175 325);
DOT 1 (-6450 825);
DOT 1 (-6175 825);
DOT 1 (-6175 1225);
DOT 1 (-4675 900);
DOT 1 (-6200 2150);
DOT 1 (-5575 3050);
DOT 1 (-5575 3100);
DOT 1 (-5575 3250);
DOT 1 (-5575 3450);
DOT 1 (-5000 3050);
DOT 1 (-5000 3300);
DOT 1 (-5575 3550);
DOT 1 (-5575 3500);
DOT 1 (-5575 3600);
DOT 1 (-5575 3700);
DOT 1 (-5575 3650);
DOT 1 (-5575 3800);
DOT 1 (-5575 3850);
DOT 1 (-5575 3750);
DOT 1 (-5575 3900);
DOT 1 (-5575 3950);
DOT 1 (-5575 4000);
DOT 1 (-5575 4050);
DOT 1 (-5575 4100);
DOT 1 (-5575 4150);
DOT 1 (-5575 4200);
DOT 1 (-5575 4250);
DOT 1 (-5575 4300);
DOT 1 (-5000 3550);
DOT 1 (-5000 3800);
DOT 1 (-5000 4050);
DOT 1 (-4950 4550);
DOT 1 (-4775 4550);
DOT 1 (-4950 4825);
DOT 1 (-4775 4825);
DOT 1 (-2600 3100);
DOT 1 (-2600 3150);
DOT 1 (-2600 3200);
DOT 1 (-2600 3250);
DOT 1 (-2600 3300);
DOT 1 (-2600 3350);
DOT 1 (-2600 3400);
DOT 1 (-4450 4550);
DOT 1 (-4450 4825);
DOT 1 (-2600 3600);
DOT 1 (-2600 3650);
DOT 1 (-2600 3700);
DOT 1 (-2600 3750);
DOT 1 (-2600 3800);
DOT 1 (-2600 3850);
DOT 1 (-2600 3900);
DOT 1 (-2600 3950);
DOT 1 (-2600 4000);
DOT 1 (-1150 1200);
DOT 1 (-1150 1300);
DOT 1 (-1150 1350);
DOT 1 (-1150 1400);
DOT 1 (-1150 1500);
DOT 1 (-1150 1450);
DOT 1 (-1150 1550);
DOT 1 (-1150 1600);
DOT 1 (-1150 1750);
DOT 1 (-1150 1800);
DOT 1 (-1150 1850);
DOT 1 (-1150 1900);
DOT 1 (-1150 1950);
DOT 1 (-1150 2000);
DOT 1 (-1150 2050);
DOT 1 (-1150 2100);
DOT 1 (-1150 2150);
DOT 1 (-1725 4600);
DOT 1 (-5575 3200);
DOT 1 (-1150 1700);
DOT 1 (-5575 3300);
DOT 1 (-5575 3150);
DOT 1 (-5575 3400);
DOT 1 (-5575 3350);
DOT 1 (-7900 3050);
DOT 1 (-7900 3100);
DOT 1 (-7900 3150);
DOT 1 (-7900 3200);
DOT 1 (-7900 3250);
DOT 1 (-7900 3300);
DOT 1 (-7900 3350);
DOT 1 (-7900 3400);
DOT 1 (-7900 3450);
DOT 1 (-7900 3500);
DOT 1 (-7900 3550);
DOT 1 (-7900 3600);
DOT 1 (-7900 3650);
DOT 1 (-7900 3700);
DOT 1 (-7900 3750);
DOT 1 (-7900 3800);
DOT 1 (-7900 3850);
DOT 1 (-7900 3900);
DOT 1 (-7900 3950);
DOT 1 (-7900 4000);
DOT 1 (-7900 4050);
DOT 1 (-7900 4100);
DOT 1 (-7900 4150);
DOT 1 (-7900 4200);
DOT 1 (-7900 4250);
DOT 1 (-3400 2900);
FORCENOTE
ROOM=SM_CONTROLLER
(-7483 348) 0;
DISPLAY LEFT (-7483 348);
DISPLAY 0.617021 (-7483 348);
PAINT PURPLE (-7483 348);
FORCENOTE
TRACE WIDTH >= 15 MILS
(-5975 675) 0;
DISPLAY LEFT (-5975 675);
DISPLAY 1.021277 (-5975 675);
PAINT PURPLE (-5975 675);
FORCENOTE
NEED TO CHECK
(-3625 4950) 0;
DISPLAY LEFT (-3625 4950);
DISPLAY 1.021277 (-3625 4950);
PAINT RED (-3625 4950);
QUIT
